FILE_TYPE = MACRO_DRAWING;
SET COLOR_WIRE YELLOW;
SET COLOR_PROP ORANGE;
SET COLOR_DOT WHITE;
SET COLOR_ARC YELLOW;
SET COLOR_BODY GREEN;
SET COLOR_NOTE PURPLE;
SET PROP_DISPLAY VALUE;
SET PAGE_NUMBER P36;
SET PATH_NUMBER P82;
FORCEADD LCMXO3LF2100C5BG256C..3
(-4800 4150);
FORCEPROP 2 LAST PART_TYPE SMLF
J 0
(-5400 5750);
DISPLAY 0.680851 (-5400 5750);
FORCEPROP 1 LAST MATERIAL IC
J 0
(-5416 5485);
DISPLAY 0.723404 (-5416 5485);
PAINT GREEN (-5416 5485);
FORCEPROP 1 LAST PART_NUMBER AJ021000T03
J 0
(-5416 5570);
DISPLAY 0.723404 (-5416 5570);
PAINT GREEN (-5416 5570);
FORCEPROP 2 LAST VALUE LCMXO3LF-2100C-5BG256C
J 0
(-5400 5700);
DISPLAY 0.680851 (-5400 5700);
FORCEPROP 2 LAST CDS_LIB pure_quanta
J 0
(-4800 4150);
DISPLAY INVISIBLE (-4800 4150);
FORCEPROP 1 LAST PATH I1
J 0
(-4800 4150);
DISPLAY 0.723404 (-4800 4150);
PAINT GREEN (-4800 4150);
DISPLAY INVISIBLE (-4800 4150);
FORCEPROP 1 LAST CDS_LMAN_SYM_OUTLINE -625,1325,625,-1325
J 0
(-4800 4150);
DISPLAY 0.468085 (-4800 4150);
PAINT GREEN (-4800 4150);
DISPLAY INVISIBLE (-4800 4150);
FORCEPROP 1 LAST NEEDS_NO_SIZE TRUE
J 0
(-4800 4150);
DISPLAY 0.723404 (-4800 4150);
PAINT GREEN (-4800 4150);
DISPLAY INVISIBLE (-4800 4150);
FORCEPROP 1 LAST LOCATION U25
J 0
(-5416 5657);
DISPLAY 0.723404 (-5416 5657);
PAINT GREEN (-5416 5657);
FORCEPROP 0 LASTPIN (-5575 5275) $PN P4
J 2
(-5585 5285);
DISPLAY 0.680851 (-5585 5285);
PAINT MONO (-5585 5285);
FORCEPROP 0 LASTPIN (-5575 5225) $PN T4
J 2
(-5585 5235);
DISPLAY 0.680851 (-5585 5235);
PAINT MONO (-5585 5235);
FORCEPROP 0 LASTPIN (-5575 5125) $PN T2
J 2
(-5585 5135);
DISPLAY 0.680851 (-5585 5135);
PAINT MONO (-5585 5135);
FORCEPROP 0 LASTPIN (-5575 5075) $PN R3
J 2
(-5585 5085);
DISPLAY 0.680851 (-5585 5085);
PAINT MONO (-5585 5085);
FORCEPROP 0 LASTPIN (-5575 4975) $PN R5
J 2
(-5585 4985);
DISPLAY 0.680851 (-5585 4985);
PAINT MONO (-5585 4985);
FORCEPROP 0 LASTPIN (-5575 4925) $PN P5
J 2
(-5585 4935);
DISPLAY 0.680851 (-5585 4935);
PAINT MONO (-5585 4935);
FORCEPROP 0 LASTPIN (-5575 4675) $PN T5
J 2
(-5585 4685);
DISPLAY 0.680851 (-5585 4685);
PAINT MONO (-5585 4685);
FORCEPROP 0 LASTPIN (-5575 4625) $PN R6
J 2
(-5585 4635);
DISPLAY 0.680851 (-5585 4635);
PAINT MONO (-5585 4635);
FORCEPROP 0 LASTPIN (-5575 4825) $PN T3
J 2
(-5585 4835);
DISPLAY 0.680851 (-5585 4835);
PAINT MONO (-5585 4835);
FORCEPROP 0 LASTPIN (-5575 4775) $PN R4
J 2
(-5585 4785);
DISPLAY 0.680851 (-5585 4785);
PAINT MONO (-5585 4785);
FORCEPROP 0 LASTPIN (-5575 4375) $PN P6
J 2
(-5585 4385);
DISPLAY 0.680851 (-5585 4385);
PAINT MONO (-5585 4385);
FORCEPROP 0 LASTPIN (-5575 4325) $PN T6
J 2
(-5585 4335);
DISPLAY 0.680851 (-5585 4335);
PAINT MONO (-5585 4335);
FORCEPROP 0 LASTPIN (-5575 4525) $PN N6
J 2
(-5585 4535);
DISPLAY 0.680851 (-5585 4535);
PAINT MONO (-5585 4535);
FORCEPROP 0 LASTPIN (-5575 4475) $PN L7
J 2
(-5585 4485);
DISPLAY 0.680851 (-5585 4485);
PAINT MONO (-5585 4485);
FORCEPROP 0 LASTPIN (-5575 4225) $PN R7
J 2
(-5585 4235);
DISPLAY 0.680851 (-5585 4235);
PAINT MONO (-5585 4235);
FORCEPROP 0 LASTPIN (-5575 4175) $PN P7
J 2
(-5585 4185);
DISPLAY 0.680851 (-5585 4185);
PAINT MONO (-5585 4185);
FORCEPROP 0 LASTPIN (-5575 4075) $PN M7
J 2
(-5585 4085);
DISPLAY 0.680851 (-5585 4085);
PAINT MONO (-5585 4085);
FORCEPROP 0 LASTPIN (-5575 4025) $PN N7
J 2
(-5585 4035);
DISPLAY 0.680851 (-5585 4035);
PAINT MONO (-5585 4035);
FORCEPROP 0 LASTPIN (-5575 3725) $PN T7
J 2
(-5585 3735);
DISPLAY 0.680851 (-5585 3735);
PAINT MONO (-5585 3735);
FORCEPROP 0 LASTPIN (-5575 3675) $PN R8
J 2
(-5585 3685);
DISPLAY 0.680851 (-5585 3685);
PAINT MONO (-5585 3685);
FORCEPROP 0 LASTPIN (-5575 3925) $PN M6
J 2
(-5585 3935);
DISPLAY 0.680851 (-5585 3935);
PAINT MONO (-5585 3935);
FORCEPROP 0 LASTPIN (-5575 3875) $PN L8
J 2
(-5585 3885);
DISPLAY 0.680851 (-5585 3885);
PAINT MONO (-5585 3885);
FORCEPROP 0 LASTPIN (-5575 3575) $PN P8
J 2
(-5585 3585);
DISPLAY 0.680851 (-5585 3585);
PAINT MONO (-5585 3585);
FORCEPROP 0 LASTPIN (-5575 3525) $PN T8
J 2
(-5585 3535);
DISPLAY 0.680851 (-5585 3535);
PAINT MONO (-5585 3535);
FORCEPROP 0 LASTPIN (-5575 3425) $PN N8
J 2
(-5585 3435);
DISPLAY 0.680851 (-5585 3435);
PAINT MONO (-5585 3435);
FORCEPROP 0 LASTPIN (-5575 3375) $PN L9
J 2
(-5585 3385);
DISPLAY 0.680851 (-5585 3385);
PAINT MONO (-5585 3385);
FORCEPROP 0 LASTPIN (-4025 5125) $PN T9
J 0
(-4015 5135);
DISPLAY 0.680851 (-4015 5135);
PAINT MONO (-4015 5135);
FORCEPROP 0 LASTPIN (-4025 5075) $PN P9
J 0
(-4015 5085);
DISPLAY 0.680851 (-4015 5085);
PAINT MONO (-4015 5085);
FORCEPROP 0 LASTPIN (-4025 5275) $PN M8
J 0
(-4015 5285);
DISPLAY 0.680851 (-4015 5285);
PAINT MONO (-4015 5285);
FORCEPROP 0 LASTPIN (-4025 5225) $PN N9
J 0
(-4015 5235);
DISPLAY 0.680851 (-4015 5235);
PAINT MONO (-4015 5235);
FORCEPROP 0 LASTPIN (-4025 4975) $PN R9
J 0
(-4015 4985);
DISPLAY 0.680851 (-4015 4985);
PAINT MONO (-4015 4985);
FORCEPROP 0 LASTPIN (-4025 4925) $PN T10
J 0
(-4015 4935);
DISPLAY 0.680851 (-4015 4935);
PAINT MONO (-4015 4935);
FORCEPROP 0 LASTPIN (-4025 4825) $PN M9
J 0
(-4015 4835);
DISPLAY 0.680851 (-4015 4835);
PAINT MONO (-4015 4835);
FORCEPROP 0 LASTPIN (-4025 4775) $PN L10
J 0
(-4015 4785);
DISPLAY 0.680851 (-4015 4785);
PAINT MONO (-4015 4785);
FORCEPROP 0 LASTPIN (-4025 4525) $PN P10
J 0
(-4015 4535);
DISPLAY 0.680851 (-4015 4535);
PAINT MONO (-4015 4535);
FORCEPROP 0 LASTPIN (-4025 4475) $PN R10
J 0
(-4015 4485);
DISPLAY 0.680851 (-4015 4485);
PAINT MONO (-4015 4485);
FORCEPROP 0 LASTPIN (-4025 4675) $PN N10
J 0
(-4015 4685);
DISPLAY 0.680851 (-4015 4685);
PAINT MONO (-4015 4685);
FORCEPROP 0 LASTPIN (-4025 4625) $PN M11
J 0
(-4015 4635);
DISPLAY 0.680851 (-4015 4635);
PAINT MONO (-4015 4635);
FORCEPROP 0 LASTPIN (-4025 4375) $PN T11
J 0
(-4015 4385);
DISPLAY 0.680851 (-4015 4385);
PAINT MONO (-4015 4385);
FORCEPROP 0 LASTPIN (-4025 4325) $PN P11
J 0
(-4015 4335);
DISPLAY 0.680851 (-4015 4335);
PAINT MONO (-4015 4335);
FORCEPROP 0 LASTPIN (-4025 4225) $PN M10
J 0
(-4015 4235);
DISPLAY 0.680851 (-4015 4235);
PAINT MONO (-4015 4235);
FORCEPROP 0 LASTPIN (-4025 4175) $PN N11
J 0
(-4015 4185);
DISPLAY 0.680851 (-4015 4185);
PAINT MONO (-4015 4185);
FORCEPROP 0 LASTPIN (-4025 3875) $PN R11
J 0
(-4015 3885);
DISPLAY 0.680851 (-4015 3885);
PAINT MONO (-4015 3885);
FORCEPROP 0 LASTPIN (-4025 3825) $PN T12
J 0
(-4015 3835);
DISPLAY 0.680851 (-4015 3835);
PAINT MONO (-4015 3835);
FORCEPROP 0 LASTPIN (-4025 4025) $PN R13
J 0
(-4015 4035);
DISPLAY 0.680851 (-4015 4035);
PAINT MONO (-4015 4035);
FORCEPROP 0 LASTPIN (-4025 3975) $PN T14
J 0
(-4015 3985);
DISPLAY 0.680851 (-4015 3985);
PAINT MONO (-4015 3985);
FORCEPROP 0 LASTPIN (-4025 3725) $PN P12
J 0
(-4015 3735);
DISPLAY 0.680851 (-4015 3735);
PAINT MONO (-4015 3735);
FORCEPROP 0 LASTPIN (-4025 3675) $PN T13
J 0
(-4015 3685);
DISPLAY 0.680851 (-4015 3685);
PAINT MONO (-4015 3685);
FORCEPROP 0 LASTPIN (-4025 3575) $PN R12
J 0
(-4015 3585);
DISPLAY 0.680851 (-4015 3585);
PAINT MONO (-4015 3585);
FORCEPROP 0 LASTPIN (-4025 3525) $PN P13
J 0
(-4015 3535);
DISPLAY 0.680851 (-4015 3535);
PAINT MONO (-4015 3535);
FORCEPROP 0 LASTPIN (-4025 3425) $PN T15
J 0
(-4015 3435);
DISPLAY 0.680851 (-4015 3435);
PAINT MONO (-4015 3435);
FORCEPROP 0 LASTPIN (-4025 3375) $PN R14
J 0
(-4015 3385);
DISPLAY 0.680851 (-4015 3385);
PAINT MONO (-4015 3385);
FORCEPROP 0 LASTPIN (-5575 3075) $PN K8
J 2
(-5585 3085);
DISPLAY 0.680851 (-5585 3085);
PAINT MONO (-5585 3085);
FORCEPROP 0 LASTPIN (-5575 3025) $PN K9
J 2
(-5585 3035);
DISPLAY 0.680851 (-5585 3035);
PAINT MONO (-5585 3035);
FORCEPROP 0 LASTPIN (-4025 3075) $PN N5
J 0
(-4015 3085);
DISPLAY 0.680851 (-4015 3085);
PAINT MONO (-4015 3085);
FORCEPROP 0 LASTPIN (-4025 3025) $PN N12
J 0
(-4015 3035);
DISPLAY 0.680851 (-4015 3035);
PAINT MONO (-4015 3035);
FORCEPROP 0 LAST $SEC 3
J 0
(-5400 5800);
DISPLAY 0.680851 (-5400 5800);
PAINT MONO (-5400 5800);
DISPLAY INVISIBLE (-5400 5800);
FORCEPROP 0 LAST CDS_SEC 3
J 0
(-5400 5800);
DISPLAY 0.680851 (-5400 5800);
DISPLAY INVISIBLE (-5400 5800);
FORCEADD Q_RES..1
(-7250 4675);
FORCEPROP 1 LAST VALUE 0
J 2
(-7100 4675);
DISPLAY 0.510638 (-7100 4675);
PAINT SKYBLUE (-7100 4675);
FORCEPROP 1 LAST MATERIAL CHIP
J 0
(-7050 4675);
DISPLAY 0.510638 (-7050 4675);
PAINT SKYBLUE (-7050 4675);
FORCEPROP 1 LAST PATH I10
J 0
(-7300 4825);
DISPLAY 0.978723 (-7300 4825);
PAINT WHITE (-7300 4825);
DISPLAY INVISIBLE (-7300 4825);
FORCEPROP 1 LAST PART_NUMBER CS00002JB13
J 0
(-7350 4750);
DISPLAY 0.510638 (-7350 4750);
PAINT WHITE (-7350 4750);
DISPLAY INVISIBLE (-7350 4750);
FORCEPROP 1 LAST PACK_TYPE 0402LF
J 0
(-7275 4725);
DISPLAY 0.510638 (-7275 4725);
PAINT SKYBLUE (-7275 4725);
DISPLAY INVISIBLE (-7275 4725);
FORCEPROP 1 LAST WATTAGE 1/16W
J 2
(-6900 4775);
DISPLAY 0.510638 (-6900 4775);
PAINT SKYBLUE (-6900 4775);
DISPLAY INVISIBLE (-6900 4775);
FORCEPROP 1 LAST TOLERANCE 5%
J 0
(-7325 4775);
DISPLAY 0.510638 (-7325 4775);
PAINT SKYBLUE (-7325 4775);
DISPLAY INVISIBLE (-7325 4775);
FORCEPROP 2 LAST SEC_TYPE 0402LF
J 0
(-7300 4875);
DISPLAY 0.680851 (-7300 4875);
DISPLAY INVISIBLE (-7300 4875);
FORCEPROP 2 LAST CDS_LIB pure_quanta
J 0
(-7250 4675);
DISPLAY INVISIBLE (-7250 4675);
FORCEPROP 1 LAST LOCATION R746
J 0
(-7525 4675);
DISPLAY 0.702128 (-7525 4675);
PAINT YELLOW (-7525 4675);
FORCEPROP 1 LASTPIN (-7350 4675) $PN 1
J 0
(-7338 4687);
DISPLAY 0.808511 (-7338 4687);
PAINT WHITE (-7338 4687);
FORCEPROP 1 LASTPIN (-7150 4675) $PN 2
J 0
(-7188 4687);
DISPLAY 0.808511 (-7188 4687);
PAINT WHITE (-7188 4687);
FORCEPROP 2 LAST SEC 1
J 0
(-7300 4875);
DISPLAY 0.680851 (-7300 4875);
PAINT MONO (-7300 4875);
DISPLAY INVISIBLE (-7300 4875);
FORCEADD OFFPAGE..1
(-8500 5275);
FORCEPROP 2 LAST $XR0 15 
J 0
(-8751 5275);
DISPLAY 0.638298 (-8751 5275);
PAINT MONO (-8751 5275);
FORCEPROP 2 LAST $XR1 42 
J 0
(-8841 5275);
DISPLAY 0.638298 (-8841 5275);
PAINT MONO (-8841 5275);
FORCEPROP 2 LAST PATH I14
J 0
(-8750 5325);
DISPLAY 0.680851 (-8750 5325);
DISPLAY INVISIBLE (-8750 5325);
FORCEPROP 1 LAST COMMENT_BODY TRUE
J 0
(-8375 5175);
DISPLAY 0.872340 (-8375 5175);
PAINT GREEN (-8375 5175);
DISPLAY INVISIBLE (-8375 5175);
FORCEPROP 1 LAST OFFPAGE TRUE
J 0
(-8175 5150);
DISPLAY 0.872340 (-8175 5150);
DISPLAY INVISIBLE (-8175 5150);
FORCEPROP 2 LAST CDS_LIB standard
J 0
(-8500 5275);
DISPLAY INVISIBLE (-8500 5275);
FORCEADD OFFPAGE..1
(-8500 5125);
FORCEPROP 2 LAST $XR0 28 
J 0
(-8751 5125);
DISPLAY 0.638298 (-8751 5125);
PAINT MONO (-8751 5125);
FORCEPROP 2 LAST $XR1 10 
J 0
(-8841 5125);
DISPLAY 0.638298 (-8841 5125);
PAINT MONO (-8841 5125);
FORCEPROP 2 LAST $XR2 15 
J 0
(-8931 5125);
DISPLAY 0.638298 (-8931 5125);
PAINT MONO (-8931 5125);
FORCEPROP 2 LAST PATH I16
J 0
(-8700 5175);
DISPLAY 0.680851 (-8700 5175);
DISPLAY INVISIBLE (-8700 5175);
FORCEPROP 1 LAST COMMENT_BODY TRUE
J 0
(-8375 5025);
DISPLAY 0.872340 (-8375 5025);
PAINT GREEN (-8375 5025);
DISPLAY INVISIBLE (-8375 5025);
FORCEPROP 1 LAST OFFPAGE TRUE
J 0
(-8175 5000);
DISPLAY 0.872340 (-8175 5000);
DISPLAY INVISIBLE (-8175 5000);
FORCEPROP 2 LAST CDS_LIB standard
J 0
(-8500 5125);
DISPLAY INVISIBLE (-8500 5125);
FORCEADD OFFPAGE..5
(-8500 5075);
FORCEPROP 2 LAST $XR0 42 
J 0
(-8754 5075);
DISPLAY 0.638298 (-8754 5075);
PAINT MONO (-8754 5075);
FORCEPROP 2 LAST $XR1 13 
J 0
(-8844 5075);
DISPLAY 0.638298 (-8844 5075);
PAINT MONO (-8844 5075);
FORCEPROP 2 LAST $XR2 28 
J 0
(-8934 5075);
DISPLAY 0.638298 (-8934 5075);
PAINT MONO (-8934 5075);
FORCEPROP 2 LASTPIN (-8450 5075) SIG_NAME PWRGD_DSW_PWROK
J 0
(-8460 5085);
DISPLAY 0.851064 (-8460 5085);
FORCEPROP 2 LAST PATH I17
J 0
(-8750 5125);
DISPLAY 0.680851 (-8750 5125);
DISPLAY INVISIBLE (-8750 5125);
FORCEPROP 1 LAST COMMENT_BODY TRUE
J 0
(-8400 5000);
DISPLAY 0.872340 (-8400 5000);
PAINT GREEN (-8400 5000);
DISPLAY INVISIBLE (-8400 5000);
FORCEPROP 1 LAST OFFPAGE TRUE
J 0
(-8175 4950);
DISPLAY 0.872340 (-8175 4950);
DISPLAY INVISIBLE (-8175 4950);
FORCEPROP 2 LAST CDS_LIB standard
J 0
(-8500 5075);
DISPLAY INVISIBLE (-8500 5075);
FORCEADD OFFPAGE..1
(-8500 4975);
FORCEPROP 2 LAST $XR0 29 
J 0
(-8751 4975);
DISPLAY 0.638298 (-8751 4975);
PAINT MONO (-8751 4975);
FORCEPROP 2 LAST $XR1 13 
J 0
(-8841 4975);
DISPLAY 0.638298 (-8841 4975);
PAINT MONO (-8841 4975);
FORCEPROP 2 LAST PATH I18
J 0
(-8750 5025);
DISPLAY 0.680851 (-8750 5025);
DISPLAY INVISIBLE (-8750 5025);
FORCEPROP 1 LAST COMMENT_BODY TRUE
J 0
(-8375 4875);
DISPLAY 0.872340 (-8375 4875);
PAINT GREEN (-8375 4875);
DISPLAY INVISIBLE (-8375 4875);
FORCEPROP 1 LAST OFFPAGE TRUE
J 0
(-8175 4850);
DISPLAY 0.872340 (-8175 4850);
DISPLAY INVISIBLE (-8175 4850);
FORCEPROP 2 LAST CDS_LIB standard
J 0
(-8500 4975);
DISPLAY INVISIBLE (-8500 4975);
FORCEADD OFFPAGE..1
(-8500 4775);
FORCEPROP 2 LAST $XR0 13 
J 0
(-8751 4775);
DISPLAY 0.638298 (-8751 4775);
PAINT MONO (-8751 4775);
FORCEPROP 2 LAST PATH I19
J 0
(-8750 4825);
DISPLAY 0.680851 (-8750 4825);
DISPLAY INVISIBLE (-8750 4825);
FORCEPROP 1 LAST COMMENT_BODY TRUE
J 0
(-8375 4675);
DISPLAY 0.872340 (-8375 4675);
PAINT GREEN (-8375 4675);
DISPLAY INVISIBLE (-8375 4675);
FORCEPROP 1 LAST OFFPAGE TRUE
J 0
(-8175 4650);
DISPLAY 0.872340 (-8175 4650);
DISPLAY INVISIBLE (-8175 4650);
FORCEPROP 2 LAST CDS_LIB standard
J 0
(-8500 4775);
DISPLAY INVISIBLE (-8500 4775);
FORCEADD Q_RES..1
(-7250 5275);
FORCEPROP 1 LAST VALUE 0
J 2
(-7100 5275);
DISPLAY 0.510638 (-7100 5275);
PAINT SKYBLUE (-7100 5275);
FORCEPROP 1 LAST MATERIAL CHIP
J 0
(-7050 5275);
DISPLAY 0.510638 (-7050 5275);
PAINT SKYBLUE (-7050 5275);
FORCEPROP 1 LAST PATH I2
J 0
(-7300 5425);
DISPLAY 0.978723 (-7300 5425);
PAINT WHITE (-7300 5425);
DISPLAY INVISIBLE (-7300 5425);
FORCEPROP 1 LAST PART_NUMBER CS00002JB13
J 0
(-7350 5350);
DISPLAY 0.510638 (-7350 5350);
PAINT WHITE (-7350 5350);
DISPLAY INVISIBLE (-7350 5350);
FORCEPROP 1 LAST PACK_TYPE 0402LF
J 0
(-7275 5325);
DISPLAY 0.510638 (-7275 5325);
PAINT SKYBLUE (-7275 5325);
DISPLAY INVISIBLE (-7275 5325);
FORCEPROP 1 LAST WATTAGE 1/16W
J 2
(-6900 5375);
DISPLAY 0.510638 (-6900 5375);
PAINT SKYBLUE (-6900 5375);
DISPLAY INVISIBLE (-6900 5375);
FORCEPROP 1 LAST TOLERANCE 5%
J 0
(-7325 5375);
DISPLAY 0.510638 (-7325 5375);
PAINT SKYBLUE (-7325 5375);
DISPLAY INVISIBLE (-7325 5375);
FORCEPROP 2 LAST CDS_LIB pure_quanta
J 0
(-7250 5275);
DISPLAY INVISIBLE (-7250 5275);
FORCEPROP 2 LAST SEC_TYPE 0402LF
J 0
(-7300 5475);
DISPLAY 0.680851 (-7300 5475);
DISPLAY INVISIBLE (-7300 5475);
FORCEPROP 1 LAST LOCATION R575
J 0
(-7525 5275);
DISPLAY 0.702128 (-7525 5275);
PAINT YELLOW (-7525 5275);
FORCEPROP 1 LASTPIN (-7350 5275) $PN 1
J 0
(-7338 5287);
DISPLAY 0.808511 (-7338 5287);
PAINT WHITE (-7338 5287);
FORCEPROP 1 LASTPIN (-7150 5275) $PN 2
J 0
(-7188 5287);
DISPLAY 0.808511 (-7188 5287);
PAINT WHITE (-7188 5287);
FORCEPROP 2 LAST SEC 1
J 0
(-7300 5475);
DISPLAY 0.680851 (-7300 5475);
PAINT MONO (-7300 5475);
DISPLAY INVISIBLE (-7300 5475);
FORCEADD OFFPAGE..5
(-8500 4825);
FORCEPROP 2 LAST $XR0 13 
J 0
(-8754 4825);
DISPLAY 0.638298 (-8754 4825);
PAINT MONO (-8754 4825);
FORCEPROP 2 LAST PATH I20
J 0
(-8750 4875);
DISPLAY 0.680851 (-8750 4875);
DISPLAY INVISIBLE (-8750 4875);
FORCEPROP 1 LAST COMMENT_BODY TRUE
J 0
(-8400 4750);
DISPLAY 0.872340 (-8400 4750);
PAINT GREEN (-8400 4750);
DISPLAY INVISIBLE (-8400 4750);
FORCEPROP 1 LAST OFFPAGE TRUE
J 0
(-8175 4700);
DISPLAY 0.872340 (-8175 4700);
DISPLAY INVISIBLE (-8175 4700);
FORCEPROP 2 LAST CDS_LIB standard
J 0
(-8500 4825);
DISPLAY INVISIBLE (-8500 4825);
FORCEADD OFFPAGE..1
(-8500 4675);
FORCEPROP 2 LAST $XR0 46 
J 0
(-8751 4675);
DISPLAY 0.638298 (-8751 4675);
PAINT MONO (-8751 4675);
FORCEPROP 2 LAST $XR1 15 
J 0
(-8841 4675);
DISPLAY 0.638298 (-8841 4675);
PAINT MONO (-8841 4675);
FORCEPROP 2 LAST CDS_LIB standard
J 0
(-8500 4675);
DISPLAY INVISIBLE (-8500 4675);
FORCEPROP 1 LAST OFFPAGE TRUE
J 0
(-8175 4550);
DISPLAY 0.872340 (-8175 4550);
DISPLAY INVISIBLE (-8175 4550);
FORCEPROP 1 LAST COMMENT_BODY TRUE
J 0
(-8375 4575);
DISPLAY 0.872340 (-8375 4575);
PAINT GREEN (-8375 4575);
DISPLAY INVISIBLE (-8375 4575);
FORCEPROP 2 LAST PATH I21
J 0
(-8700 4725);
DISPLAY 0.680851 (-8700 4725);
DISPLAY INVISIBLE (-8700 4725);
FORCEADD OFFPAGE..1
(-8500 4625);
FORCEPROP 2 LAST $XR0 13 
J 0
(-8751 4625);
DISPLAY 0.638298 (-8751 4625);
PAINT MONO (-8751 4625);
FORCEPROP 2 LAST $XR1 42 
J 0
(-8841 4625);
DISPLAY 0.638298 (-8841 4625);
PAINT MONO (-8841 4625);
FORCEPROP 2 LAST CDS_LIB standard
J 0
(-8500 4625);
DISPLAY INVISIBLE (-8500 4625);
FORCEPROP 1 LAST OFFPAGE TRUE
J 0
(-8175 4500);
DISPLAY 0.872340 (-8175 4500);
DISPLAY INVISIBLE (-8175 4500);
FORCEPROP 1 LAST COMMENT_BODY TRUE
J 0
(-8375 4525);
DISPLAY 0.872340 (-8375 4525);
PAINT GREEN (-8375 4525);
DISPLAY INVISIBLE (-8375 4525);
FORCEPROP 2 LAST PATH I22
J 0
(-8700 4675);
DISPLAY 0.680851 (-8700 4675);
DISPLAY INVISIBLE (-8700 4675);
FORCEADD OFFPAGE..5
(-8500 4525);
FORCEPROP 2 LAST $XR0 13 
J 0
(-8754 4525);
DISPLAY 0.638298 (-8754 4525);
PAINT MONO (-8754 4525);
FORCEPROP 2 LAST $XR1 48 
J 0
(-8844 4525);
DISPLAY 0.638298 (-8844 4525);
PAINT MONO (-8844 4525);
FORCEPROP 1 LAST COMMENT_BODY TRUE
J 0
(-8400 4450);
DISPLAY 0.872340 (-8400 4450);
PAINT GREEN (-8400 4450);
DISPLAY INVISIBLE (-8400 4450);
FORCEPROP 1 LAST OFFPAGE TRUE
J 0
(-8175 4400);
DISPLAY 0.872340 (-8175 4400);
DISPLAY INVISIBLE (-8175 4400);
FORCEPROP 2 LAST CDS_LIB standard
J 0
(-8500 4525);
DISPLAY INVISIBLE (-8500 4525);
FORCEPROP 2 LAST PATH I23
J 0
(-8750 4575);
DISPLAY 0.680851 (-8750 4575);
DISPLAY INVISIBLE (-8750 4575);
FORCEADD OFFPAGE..4
(-1525 5275);
FORCEPROP 2 LAST $XR0 54 
J 0
(-1339 5275);
DISPLAY 0.638298 (-1339 5275);
PAINT MONO (-1339 5275);
FORCEPROP 2 LAST $XR1 52 
J 0
(-1249 5275);
DISPLAY 0.638298 (-1249 5275);
PAINT MONO (-1249 5275);
FORCEPROP 2 LAST $XR2 55 
J 0
(-1159 5275);
DISPLAY 0.638298 (-1159 5275);
PAINT MONO (-1159 5275);
FORCEPROP 2 LAST PATH I27
J 0
(-1150 5325);
DISPLAY 0.680851 (-1150 5325);
DISPLAY INVISIBLE (-1150 5325);
FORCEPROP 2 LAST CDS_LIB standard
J 0
(-1525 5275);
DISPLAY INVISIBLE (-1525 5275);
FORCEPROP 1 LAST OFFPAGE TRUE
J 0
(-1200 5150);
DISPLAY 0.872340 (-1200 5150);
PAINT GREEN (-1200 5150);
DISPLAY INVISIBLE (-1200 5150);
FORCEPROP 1 LAST COMMENT_BODY TRUE
J 0
(-1550 5175);
DISPLAY 0.872340 (-1550 5175);
PAINT PEACH (-1550 5175);
DISPLAY INVISIBLE (-1550 5175);
FORCEADD OFFPAGE..4
(-1525 5225);
FORCEPROP 2 LAST $XR0 52 
J 0
(-1339 5225);
DISPLAY 0.638298 (-1339 5225);
PAINT MONO (-1339 5225);
FORCEPROP 2 LAST $XR1 54 
J 0
(-1249 5225);
DISPLAY 0.638298 (-1249 5225);
PAINT MONO (-1249 5225);
FORCEPROP 2 LAST $XR2 55 
J 0
(-1159 5225);
DISPLAY 0.638298 (-1159 5225);
PAINT MONO (-1159 5225);
FORCEPROP 2 LAST PATH I28
J 0
(-1225 5275);
DISPLAY 0.680851 (-1225 5275);
DISPLAY INVISIBLE (-1225 5275);
FORCEPROP 2 LAST CDS_LIB standard
J 0
(-1525 5225);
DISPLAY INVISIBLE (-1525 5225);
FORCEPROP 1 LAST OFFPAGE TRUE
J 0
(-1200 5100);
DISPLAY 0.872340 (-1200 5100);
PAINT GREEN (-1200 5100);
DISPLAY INVISIBLE (-1200 5100);
FORCEPROP 1 LAST COMMENT_BODY TRUE
J 0
(-1550 5125);
DISPLAY 0.872340 (-1550 5125);
PAINT PEACH (-1550 5125);
DISPLAY INVISIBLE (-1550 5125);
FORCEADD OFFPAGE..4
(-1525 5125);
FORCEPROP 2 LAST $XR0 55 
J 0
(-1339 5125);
DISPLAY 0.638298 (-1339 5125);
PAINT MONO (-1339 5125);
FORCEPROP 2 LAST $XR1 56 
J 0
(-1249 5125);
DISPLAY 0.638298 (-1249 5125);
PAINT MONO (-1249 5125);
FORCEPROP 1 LAST COMMENT_BODY TRUE
J 0
(-1550 5025);
DISPLAY 0.872340 (-1550 5025);
PAINT PEACH (-1550 5025);
DISPLAY INVISIBLE (-1550 5025);
FORCEPROP 1 LAST OFFPAGE TRUE
J 0
(-1200 5000);
DISPLAY 0.872340 (-1200 5000);
PAINT GREEN (-1200 5000);
DISPLAY INVISIBLE (-1200 5000);
FORCEPROP 2 LAST CDS_LIB standard
J 0
(-1525 5125);
DISPLAY INVISIBLE (-1525 5125);
FORCEPROP 2 LAST PATH I29
J 0
(-1225 5175);
DISPLAY 0.680851 (-1225 5175);
DISPLAY INVISIBLE (-1225 5175);
FORCEADD Q_RES..1
(-7250 5125);
FORCEPROP 1 LAST VALUE 0
J 2
(-7100 5125);
DISPLAY 0.510638 (-7100 5125);
PAINT SKYBLUE (-7100 5125);
FORCEPROP 1 LAST MATERIAL CHIP
J 0
(-7050 5125);
DISPLAY 0.510638 (-7050 5125);
PAINT SKYBLUE (-7050 5125);
FORCEPROP 1 LAST PATH I3
J 0
(-7300 5275);
DISPLAY 0.978723 (-7300 5275);
PAINT WHITE (-7300 5275);
DISPLAY INVISIBLE (-7300 5275);
FORCEPROP 1 LAST PART_NUMBER CS00002JB13
J 0
(-7350 5200);
DISPLAY 0.510638 (-7350 5200);
PAINT WHITE (-7350 5200);
DISPLAY INVISIBLE (-7350 5200);
FORCEPROP 1 LAST PACK_TYPE 0402LF
J 0
(-7275 5175);
DISPLAY 0.510638 (-7275 5175);
PAINT SKYBLUE (-7275 5175);
DISPLAY INVISIBLE (-7275 5175);
FORCEPROP 1 LAST WATTAGE 1/16W
J 2
(-6900 5225);
DISPLAY 0.510638 (-6900 5225);
PAINT SKYBLUE (-6900 5225);
DISPLAY INVISIBLE (-6900 5225);
FORCEPROP 1 LAST TOLERANCE 5%
J 0
(-7325 5225);
DISPLAY 0.510638 (-7325 5225);
PAINT SKYBLUE (-7325 5225);
DISPLAY INVISIBLE (-7325 5225);
FORCEPROP 2 LAST CDS_LIB pure_quanta
J 0
(-7250 5125);
DISPLAY INVISIBLE (-7250 5125);
FORCEPROP 2 LAST SEC_TYPE 0402LF
J 0
(-7300 5325);
DISPLAY 0.680851 (-7300 5325);
DISPLAY INVISIBLE (-7300 5325);
FORCEPROP 1 LAST LOCATION R577
J 0
(-7525 5125);
DISPLAY 0.702128 (-7525 5125);
PAINT YELLOW (-7525 5125);
FORCEPROP 1 LASTPIN (-7350 5125) $PN 1
J 0
(-7338 5137);
DISPLAY 0.808511 (-7338 5137);
PAINT WHITE (-7338 5137);
FORCEPROP 1 LASTPIN (-7150 5125) $PN 2
J 0
(-7188 5137);
DISPLAY 0.808511 (-7188 5137);
PAINT WHITE (-7188 5137);
FORCEPROP 2 LAST SEC 1
J 0
(-7300 5325);
DISPLAY 0.680851 (-7300 5325);
PAINT MONO (-7300 5325);
DISPLAY INVISIBLE (-7300 5325);
FORCEADD OFFPAGE..4
(-1525 5075);
FORCEPROP 2 LAST $XR0 56 
J 0
(-1339 5075);
DISPLAY 0.638298 (-1339 5075);
PAINT MONO (-1339 5075);
FORCEPROP 2 LAST $XR1 22 
J 0
(-1249 5075);
DISPLAY 0.638298 (-1249 5075);
PAINT MONO (-1249 5075);
FORCEPROP 2 LAST CDS_LIB standard
J 0
(-1525 5075);
DISPLAY INVISIBLE (-1525 5075);
FORCEPROP 2 LAST PATH I30
J 0
(-1225 5125);
DISPLAY 0.680851 (-1225 5125);
DISPLAY INVISIBLE (-1225 5125);
FORCEPROP 1 LAST OFFPAGE TRUE
J 0
(-1200 4950);
DISPLAY 0.872340 (-1200 4950);
PAINT GREEN (-1200 4950);
DISPLAY INVISIBLE (-1200 4950);
FORCEPROP 1 LAST COMMENT_BODY TRUE
J 0
(-1550 4975);
DISPLAY 0.872340 (-1550 4975);
PAINT PEACH (-1550 4975);
DISPLAY INVISIBLE (-1550 4975);
FORCEADD Q_RES..1
(-2575 5275);
FORCEPROP 1 LAST VALUE 0
J 2
(-2425 5275);
DISPLAY 0.510638 (-2425 5275);
PAINT SKYBLUE (-2425 5275);
FORCEPROP 1 LAST MATERIAL CHIP
J 2
(-2250 5275);
DISPLAY 0.510638 (-2250 5275);
PAINT SKYBLUE (-2250 5275);
FORCEPROP 1 LAST PATH I33
J 0
(-2625 5425);
DISPLAY 0.978723 (-2625 5425);
PAINT WHITE (-2625 5425);
DISPLAY INVISIBLE (-2625 5425);
FORCEPROP 2 LAST SEC_TYPE 0402LF
J 0
(-2625 5475);
DISPLAY 0.680851 (-2625 5475);
DISPLAY INVISIBLE (-2625 5475);
FORCEPROP 2 LAST CDS_LIB pure_quanta
J 0
(-2575 5275);
DISPLAY INVISIBLE (-2575 5275);
FORCEPROP 1 LAST TOLERANCE 5%
J 0
(-2650 5375);
DISPLAY 0.510638 (-2650 5375);
PAINT SKYBLUE (-2650 5375);
DISPLAY INVISIBLE (-2650 5375);
FORCEPROP 1 LAST WATTAGE 1/16W
J 2
(-2225 5375);
DISPLAY 0.510638 (-2225 5375);
PAINT SKYBLUE (-2225 5375);
DISPLAY INVISIBLE (-2225 5375);
FORCEPROP 1 LAST PACK_TYPE 0402LF
J 0
(-2600 5325);
DISPLAY 0.510638 (-2600 5325);
PAINT SKYBLUE (-2600 5325);
DISPLAY INVISIBLE (-2600 5325);
FORCEPROP 1 LAST PART_NUMBER CS00002JB13
J 0
(-2675 5350);
DISPLAY 0.510638 (-2675 5350);
PAINT WHITE (-2675 5350);
DISPLAY INVISIBLE (-2675 5350);
FORCEPROP 1 LAST LOCATION R321
J 0
(-2850 5275);
DISPLAY 0.702128 (-2850 5275);
PAINT YELLOW (-2850 5275);
FORCEPROP 1 LASTPIN (-2675 5275) $PN 1
J 0
(-2663 5287);
DISPLAY 0.808511 (-2663 5287);
PAINT WHITE (-2663 5287);
FORCEPROP 1 LASTPIN (-2475 5275) $PN 2
J 0
(-2513 5287);
DISPLAY 0.808511 (-2513 5287);
PAINT WHITE (-2513 5287);
FORCEPROP 0 LAST SEC 1
J 0
(-2725 5325);
DISPLAY 0.680851 (-2725 5325);
PAINT MONO (-2725 5325);
DISPLAY INVISIBLE (-2725 5325);
FORCEADD Q_RES..1
(-2575 5125);
FORCEPROP 1 LAST VALUE 0
J 2
(-2425 5125);
DISPLAY 0.510638 (-2425 5125);
PAINT SKYBLUE (-2425 5125);
FORCEPROP 1 LAST MATERIAL CHIP
J 2
(-2250 5125);
DISPLAY 0.510638 (-2250 5125);
PAINT SKYBLUE (-2250 5125);
FORCEPROP 2 LAST CDS_LIB pure_quanta
J 0
(-2575 5125);
DISPLAY INVISIBLE (-2575 5125);
FORCEPROP 2 LAST SEC_TYPE 0402LF
J 0
(-2625 5325);
DISPLAY 0.680851 (-2625 5325);
DISPLAY INVISIBLE (-2625 5325);
FORCEPROP 1 LAST PATH I34
J 0
(-2625 5275);
DISPLAY 0.978723 (-2625 5275);
PAINT WHITE (-2625 5275);
DISPLAY INVISIBLE (-2625 5275);
FORCEPROP 1 LAST TOLERANCE 5%
J 0
(-2650 5225);
DISPLAY 0.510638 (-2650 5225);
PAINT SKYBLUE (-2650 5225);
DISPLAY INVISIBLE (-2650 5225);
FORCEPROP 1 LAST WATTAGE 1/16W
J 2
(-2225 5225);
DISPLAY 0.510638 (-2225 5225);
PAINT SKYBLUE (-2225 5225);
DISPLAY INVISIBLE (-2225 5225);
FORCEPROP 1 LAST PACK_TYPE 0402LF
J 0
(-2600 5175);
DISPLAY 0.510638 (-2600 5175);
PAINT SKYBLUE (-2600 5175);
DISPLAY INVISIBLE (-2600 5175);
FORCEPROP 1 LAST PART_NUMBER CS00002JB13
J 0
(-2675 5200);
DISPLAY 0.510638 (-2675 5200);
PAINT WHITE (-2675 5200);
DISPLAY INVISIBLE (-2675 5200);
FORCEPROP 1 LAST LOCATION R323
J 0
(-2850 5125);
DISPLAY 0.702128 (-2850 5125);
PAINT YELLOW (-2850 5125);
FORCEPROP 1 LASTPIN (-2675 5125) $PN 1
J 0
(-2663 5137);
DISPLAY 0.808511 (-2663 5137);
PAINT WHITE (-2663 5137);
FORCEPROP 1 LASTPIN (-2475 5125) $PN 2
J 0
(-2513 5137);
DISPLAY 0.808511 (-2513 5137);
PAINT WHITE (-2513 5137);
FORCEPROP 0 LAST SEC 1
J 0
(-2725 5175);
DISPLAY 0.680851 (-2725 5175);
PAINT MONO (-2725 5175);
DISPLAY INVISIBLE (-2725 5175);
FORCEADD Q_RES..1
(-2575 5225);
FORCEPROP 1 LAST VALUE 0
J 2
(-2425 5225);
DISPLAY 0.510638 (-2425 5225);
PAINT SKYBLUE (-2425 5225);
FORCEPROP 1 LAST MATERIAL CHIP
J 2
(-2250 5225);
DISPLAY 0.510638 (-2250 5225);
PAINT SKYBLUE (-2250 5225);
FORCEPROP 1 LAST PATH I35
J 0
(-2625 5375);
DISPLAY 0.978723 (-2625 5375);
PAINT WHITE (-2625 5375);
DISPLAY INVISIBLE (-2625 5375);
FORCEPROP 2 LAST SEC_TYPE 0402LF
J 0
(-2625 5425);
DISPLAY 0.680851 (-2625 5425);
DISPLAY INVISIBLE (-2625 5425);
FORCEPROP 2 LAST CDS_LIB pure_quanta
J 0
(-2575 5225);
DISPLAY INVISIBLE (-2575 5225);
FORCEPROP 1 LAST TOLERANCE 5%
J 0
(-2650 5325);
DISPLAY 0.510638 (-2650 5325);
PAINT SKYBLUE (-2650 5325);
DISPLAY INVISIBLE (-2650 5325);
FORCEPROP 1 LAST WATTAGE 1/16W
J 2
(-2225 5325);
DISPLAY 0.510638 (-2225 5325);
PAINT SKYBLUE (-2225 5325);
DISPLAY INVISIBLE (-2225 5325);
FORCEPROP 1 LAST PACK_TYPE 0402LF
J 0
(-2600 5275);
DISPLAY 0.510638 (-2600 5275);
PAINT SKYBLUE (-2600 5275);
DISPLAY INVISIBLE (-2600 5275);
FORCEPROP 1 LAST PART_NUMBER CS00002JB13
J 0
(-2675 5300);
DISPLAY 0.510638 (-2675 5300);
PAINT WHITE (-2675 5300);
DISPLAY INVISIBLE (-2675 5300);
FORCEPROP 1 LAST LOCATION R322
J 0
(-2850 5225);
DISPLAY 0.702128 (-2850 5225);
PAINT YELLOW (-2850 5225);
FORCEPROP 1 LASTPIN (-2675 5225) $PN 1
J 0
(-2663 5237);
DISPLAY 0.808511 (-2663 5237);
PAINT WHITE (-2663 5237);
FORCEPROP 1 LASTPIN (-2475 5225) $PN 2
J 0
(-2513 5237);
DISPLAY 0.808511 (-2513 5237);
PAINT WHITE (-2513 5237);
FORCEPROP 0 LAST SEC 1
J 0
(-2725 5275);
DISPLAY 0.680851 (-2725 5275);
PAINT MONO (-2725 5275);
DISPLAY INVISIBLE (-2725 5275);
FORCEADD Q_RES..1
(-2575 5075);
FORCEPROP 1 LAST VALUE 0
J 2
(-2425 5075);
DISPLAY 0.510638 (-2425 5075);
PAINT SKYBLUE (-2425 5075);
FORCEPROP 1 LAST MATERIAL CHIP
J 2
(-2250 5075);
DISPLAY 0.510638 (-2250 5075);
PAINT SKYBLUE (-2250 5075);
FORCEPROP 0 LAST SEC_TYPE 0402LF
J 0
(-2625 5025);
DISPLAY 0.680851 (-2625 5025);
FORCEPROP 2 LAST CDS_LIB pure_quanta
J 0
(-2575 5075);
DISPLAY INVISIBLE (-2575 5075);
FORCEPROP 1 LAST PATH I36
J 0
(-2625 5225);
DISPLAY 0.978723 (-2625 5225);
PAINT WHITE (-2625 5225);
DISPLAY INVISIBLE (-2625 5225);
FORCEPROP 1 LAST TOLERANCE 5%
J 0
(-2650 5175);
DISPLAY 0.510638 (-2650 5175);
PAINT SKYBLUE (-2650 5175);
DISPLAY INVISIBLE (-2650 5175);
FORCEPROP 1 LAST WATTAGE 1/16W
J 2
(-2225 5175);
DISPLAY 0.510638 (-2225 5175);
PAINT SKYBLUE (-2225 5175);
DISPLAY INVISIBLE (-2225 5175);
FORCEPROP 1 LAST PACK_TYPE 0402LF
J 0
(-2600 5125);
DISPLAY 0.510638 (-2600 5125);
PAINT SKYBLUE (-2600 5125);
DISPLAY INVISIBLE (-2600 5125);
FORCEPROP 1 LAST PART_NUMBER CS00002JB13
J 0
(-2675 5150);
DISPLAY 0.510638 (-2675 5150);
PAINT WHITE (-2675 5150);
DISPLAY INVISIBLE (-2675 5150);
FORCEPROP 1 LAST LOCATION R379
J 0
(-2850 5075);
DISPLAY 0.702128 (-2850 5075);
PAINT YELLOW (-2850 5075);
FORCEPROP 1 LASTPIN (-2675 5075) $PN 1
J 0
(-2663 5087);
DISPLAY 0.808511 (-2663 5087);
PAINT WHITE (-2663 5087);
FORCEPROP 1 LASTPIN (-2475 5075) $PN 2
J 0
(-2513 5087);
DISPLAY 0.808511 (-2513 5087);
PAINT WHITE (-2513 5087);
FORCEPROP 0 LAST SEC 1
J 0
(-2725 5125);
DISPLAY 0.680851 (-2725 5125);
PAINT MONO (-2725 5125);
DISPLAY INVISIBLE (-2725 5125);
FORCEADD UNIVERSAL_POWER..1
(-5950 3175);
FORCEPROP 3 LASTPIN (-5950 3125) SIG_NAME VCCIO2\g
J 0
(-5940 3135);
DISPLAY 0.659574 (-5940 3135);
PAINT MONO (-5940 3135);
DISPLAY INVISIBLE (-5940 3135);
FORCEPROP 1 LAST HDL_POWER VCCIO2
J 1
(-5950 3225);
DISPLAY 0.702128 (-5950 3225);
PAINT GREEN (-5950 3225);
FORCEPROP 1 LAST PATH I37
J 0
(-5900 3200);
DISPLAY 0.872340 (-5900 3200);
PAINT AQUA (-5900 3200);
DISPLAY INVISIBLE (-5900 3200);
FORCEPROP 2 LAST CDS_LIB logical_power
J 0
(-5950 3175);
DISPLAY INVISIBLE (-5950 3175);
FORCEADD UNIVERSAL_POWER..1
(-3650 3175);
FORCEPROP 3 LASTPIN (-3650 3125) SIG_NAME VCCIO2\g
J 0
(-3640 3135);
DISPLAY 0.659574 (-3640 3135);
PAINT MONO (-3640 3135);
DISPLAY INVISIBLE (-3640 3135);
FORCEPROP 1 LAST HDL_POWER VCCIO2
J 1
(-3650 3225);
DISPLAY 0.702128 (-3650 3225);
PAINT GREEN (-3650 3225);
FORCEPROP 2 LAST CDS_LIB logical_power
J 0
(-3650 3175);
DISPLAY INVISIBLE (-3650 3175);
FORCEPROP 1 LAST PATH I38
J 0
(-3600 3200);
DISPLAY 0.872340 (-3600 3200);
PAINT AQUA (-3600 3200);
DISPLAY INVISIBLE (-3600 3200);
FORCEADD Q_RES..1
(-2575 4825);
FORCEPROP 1 LAST VALUE 0
J 2
(-2425 4825);
DISPLAY 0.510638 (-2425 4825);
PAINT SKYBLUE (-2425 4825);
FORCEPROP 1 LAST MATERIAL CHIP
J 2
(-2250 4825);
DISPLAY 0.510638 (-2250 4825);
PAINT SKYBLUE (-2250 4825);
FORCEPROP 1 LAST PATH I42
J 0
(-2625 4975);
DISPLAY 0.978723 (-2625 4975);
PAINT WHITE (-2625 4975);
DISPLAY INVISIBLE (-2625 4975);
FORCEPROP 2 LAST SEC_TYPE 0402LF
J 0
(-2625 5025);
DISPLAY 0.680851 (-2625 5025);
DISPLAY INVISIBLE (-2625 5025);
FORCEPROP 2 LAST CDS_LIB pure_quanta
J 0
(-2575 4825);
DISPLAY INVISIBLE (-2575 4825);
FORCEPROP 1 LAST TOLERANCE 5%
J 0
(-2650 4925);
DISPLAY 0.510638 (-2650 4925);
PAINT SKYBLUE (-2650 4925);
DISPLAY INVISIBLE (-2650 4925);
FORCEPROP 1 LAST WATTAGE 1/16W
J 2
(-2225 4925);
DISPLAY 0.510638 (-2225 4925);
PAINT SKYBLUE (-2225 4925);
DISPLAY INVISIBLE (-2225 4925);
FORCEPROP 1 LAST PACK_TYPE 0402LF
J 0
(-2600 4875);
DISPLAY 0.510638 (-2600 4875);
PAINT SKYBLUE (-2600 4875);
DISPLAY INVISIBLE (-2600 4875);
FORCEPROP 1 LAST PART_NUMBER CS00002JB13
J 0
(-2675 4900);
DISPLAY 0.510638 (-2675 4900);
PAINT WHITE (-2675 4900);
DISPLAY INVISIBLE (-2675 4900);
FORCEPROP 1 LAST LOCATION R898
J 0
(-2850 4825);
DISPLAY 0.702128 (-2850 4825);
PAINT YELLOW (-2850 4825);
FORCEPROP 1 LASTPIN (-2675 4825) $PN 1
J 0
(-2663 4837);
DISPLAY 0.808511 (-2663 4837);
PAINT WHITE (-2663 4837);
FORCEPROP 1 LASTPIN (-2475 4825) $PN 2
J 0
(-2513 4837);
DISPLAY 0.808511 (-2513 4837);
PAINT WHITE (-2513 4837);
FORCEPROP 0 LAST SEC 1
J 0
(-2725 4875);
DISPLAY 0.680851 (-2725 4875);
PAINT MONO (-2725 4875);
DISPLAY INVISIBLE (-2725 4875);
FORCEADD Q_RES..1
(-2575 4775);
FORCEPROP 1 LAST VALUE 0
J 2
(-2425 4775);
DISPLAY 0.510638 (-2425 4775);
PAINT SKYBLUE (-2425 4775);
FORCEPROP 1 LAST MATERIAL CHIP
J 2
(-2250 4775);
DISPLAY 0.510638 (-2250 4775);
PAINT SKYBLUE (-2250 4775);
FORCEPROP 2 LAST CDS_LIB pure_quanta
J 0
(-2575 4775);
DISPLAY INVISIBLE (-2575 4775);
FORCEPROP 2 LAST SEC_TYPE 0402LF
J 0
(-2625 4975);
DISPLAY 0.680851 (-2625 4975);
DISPLAY INVISIBLE (-2625 4975);
FORCEPROP 1 LAST PATH I43
J 0
(-2625 4925);
DISPLAY 0.978723 (-2625 4925);
PAINT WHITE (-2625 4925);
DISPLAY INVISIBLE (-2625 4925);
FORCEPROP 1 LAST PART_NUMBER CS00002JB13
J 0
(-2675 4850);
DISPLAY 0.510638 (-2675 4850);
PAINT WHITE (-2675 4850);
DISPLAY INVISIBLE (-2675 4850);
FORCEPROP 1 LAST PACK_TYPE 0402LF
J 0
(-2600 4825);
DISPLAY 0.510638 (-2600 4825);
PAINT SKYBLUE (-2600 4825);
DISPLAY INVISIBLE (-2600 4825);
FORCEPROP 1 LAST WATTAGE 1/16W
J 2
(-2225 4875);
DISPLAY 0.510638 (-2225 4875);
PAINT SKYBLUE (-2225 4875);
DISPLAY INVISIBLE (-2225 4875);
FORCEPROP 1 LAST TOLERANCE 5%
J 0
(-2650 4875);
DISPLAY 0.510638 (-2650 4875);
PAINT SKYBLUE (-2650 4875);
DISPLAY INVISIBLE (-2650 4875);
FORCEPROP 1 LAST LOCATION R899
J 0
(-2850 4775);
DISPLAY 0.702128 (-2850 4775);
PAINT YELLOW (-2850 4775);
FORCEPROP 1 LASTPIN (-2675 4775) $PN 1
J 0
(-2663 4787);
DISPLAY 0.808511 (-2663 4787);
PAINT WHITE (-2663 4787);
FORCEPROP 1 LASTPIN (-2475 4775) $PN 2
J 0
(-2513 4787);
DISPLAY 0.808511 (-2513 4787);
PAINT WHITE (-2513 4787);
FORCEPROP 0 LAST SEC 1
J 0
(-2725 4825);
DISPLAY 0.680851 (-2725 4825);
PAINT MONO (-2725 4825);
DISPLAY INVISIBLE (-2725 4825);
FORCEADD OFFPAGE..5
R 2
(-1525 4825);
FORCEPROP 2 LAST $XR0 30 
J 0
(-1336 4825);
DISPLAY 0.638298 (-1336 4825);
PAINT MONO (-1336 4825);
FORCEPROP 2 LAST $XR1 49 
J 0
(-1246 4825);
DISPLAY 0.638298 (-1246 4825);
PAINT MONO (-1246 4825);
FORCEPROP 2 LAST CDS_LIB standard
J 2
(-1525 4825);
DISPLAY INVISIBLE (-1525 4825);
FORCEPROP 2 LAST PATH I44
J 2
(-1575 4900);
DISPLAY 0.680851 (-1575 4900);
DISPLAY INVISIBLE (-1575 4900);
FORCEPROP 1 LAST COMMENT_BODY TRUE
J 2
(-1625 4750);
DISPLAY 0.872340 (-1625 4750);
PAINT GREEN (-1625 4750);
DISPLAY INVISIBLE (-1625 4750);
FORCEPROP 1 LAST OFFPAGE TRUE
J 2
(-1850 4700);
DISPLAY 0.872340 (-1850 4700);
DISPLAY INVISIBLE (-1850 4700);
FORCEADD OFFPAGE..5
R 2
(-1525 4775);
FORCEPROP 2 LAST $XR0 30 
J 0
(-1336 4775);
DISPLAY 0.638298 (-1336 4775);
PAINT MONO (-1336 4775);
FORCEPROP 2 LAST $XR1 49 
J 0
(-1246 4775);
DISPLAY 0.638298 (-1246 4775);
PAINT MONO (-1246 4775);
FORCEPROP 1 LAST OFFPAGE TRUE
J 2
(-1850 4650);
DISPLAY 0.872340 (-1850 4650);
DISPLAY INVISIBLE (-1850 4650);
FORCEPROP 1 LAST COMMENT_BODY TRUE
J 2
(-1625 4700);
DISPLAY 0.872340 (-1625 4700);
PAINT GREEN (-1625 4700);
DISPLAY INVISIBLE (-1625 4700);
FORCEPROP 2 LAST PATH I45
J 0
(-1350 4850);
DISPLAY 0.680851 (-1350 4850);
DISPLAY INVISIBLE (-1350 4850);
FORCEPROP 2 LAST CDS_LIB standard
J 0
(-1525 4775);
DISPLAY INVISIBLE (-1525 4775);
FORCEADD Q_RES..1
(-2575 4525);
FORCEPROP 1 LAST MATERIAL CHIP
J 2
(-2275 4525);
DISPLAY 0.510638 (-2275 4525);
PAINT SKYBLUE (-2275 4525);
FORCEPROP 1 LAST VALUE 0
J 2
(-2425 4525);
DISPLAY 0.510638 (-2425 4525);
PAINT SKYBLUE (-2425 4525);
FORCEPROP 1 LAST TOLERANCE 5%
J 0
(-2650 4625);
DISPLAY 0.510638 (-2650 4625);
PAINT SKYBLUE (-2650 4625);
DISPLAY INVISIBLE (-2650 4625);
FORCEPROP 1 LAST WATTAGE 1/16W
J 2
(-2225 4625);
DISPLAY 0.510638 (-2225 4625);
PAINT SKYBLUE (-2225 4625);
DISPLAY INVISIBLE (-2225 4625);
FORCEPROP 1 LAST PACK_TYPE 0402LF
J 0
(-2600 4575);
DISPLAY 0.510638 (-2600 4575);
PAINT SKYBLUE (-2600 4575);
DISPLAY INVISIBLE (-2600 4575);
FORCEPROP 1 LAST PART_NUMBER CS00002JB13
J 0
(-2675 4600);
DISPLAY 0.510638 (-2675 4600);
PAINT WHITE (-2675 4600);
DISPLAY INVISIBLE (-2675 4600);
FORCEPROP 1 LAST PATH I46
J 0
(-2625 4675);
DISPLAY 0.978723 (-2625 4675);
PAINT WHITE (-2625 4675);
DISPLAY INVISIBLE (-2625 4675);
FORCEPROP 2 LAST CDS_LIB pure_quanta
J 0
(-2575 4525);
DISPLAY INVISIBLE (-2575 4525);
FORCEPROP 1 LAST $LOCATION R220
J 0
(-2850 4525);
DISPLAY 0.702128 (-2850 4525);
PAINT YELLOW (-2850 4525);
FORCEPROP 1 LASTPIN (-2675 4525) $PN 1
J 0
(-2663 4537);
DISPLAY 0.787234 (-2663 4537);
PAINT MONO (-2663 4537);
FORCEPROP 1 LASTPIN (-2475 4525) $PN 2
J 0
(-2513 4537);
DISPLAY 0.787234 (-2513 4537);
PAINT MONO (-2513 4537);
FORCEPROP 0 LAST CDS_LOCATION R220
J 0
(-2850 4575);
DISPLAY 0.680851 (-2850 4575);
DISPLAY INVISIBLE (-2850 4575);
FORCEPROP 0 LAST $SEC 1
J 0
(-2850 4575);
DISPLAY 0.680851 (-2850 4575);
PAINT MONO (-2850 4575);
DISPLAY INVISIBLE (-2850 4575);
FORCEPROP 0 LAST CDS_SEC 1
J 0
(-2850 4575);
DISPLAY 0.680851 (-2850 4575);
DISPLAY INVISIBLE (-2850 4575);
FORCEADD Q_RES..1
(-2575 4575);
FORCEPROP 1 LAST MATERIAL CHIP
J 2
(-2275 4575);
DISPLAY 0.510638 (-2275 4575);
PAINT SKYBLUE (-2275 4575);
FORCEPROP 1 LAST VALUE 0
J 2
(-2425 4575);
DISPLAY 0.510638 (-2425 4575);
PAINT SKYBLUE (-2425 4575);
FORCEPROP 2 LAST CDS_LIB pure_quanta
J 0
(-2575 4575);
DISPLAY INVISIBLE (-2575 4575);
FORCEPROP 1 LAST PATH I47
J 0
(-2625 4725);
DISPLAY 0.978723 (-2625 4725);
PAINT WHITE (-2625 4725);
DISPLAY INVISIBLE (-2625 4725);
FORCEPROP 1 LAST PART_NUMBER CS00002JB13
J 0
(-2675 4650);
DISPLAY 0.510638 (-2675 4650);
PAINT WHITE (-2675 4650);
DISPLAY INVISIBLE (-2675 4650);
FORCEPROP 1 LAST PACK_TYPE 0402LF
J 0
(-2600 4625);
DISPLAY 0.510638 (-2600 4625);
PAINT SKYBLUE (-2600 4625);
DISPLAY INVISIBLE (-2600 4625);
FORCEPROP 1 LAST WATTAGE 1/16W
J 2
(-2225 4675);
DISPLAY 0.510638 (-2225 4675);
PAINT SKYBLUE (-2225 4675);
DISPLAY INVISIBLE (-2225 4675);
FORCEPROP 1 LAST TOLERANCE 5%
J 0
(-2650 4675);
DISPLAY 0.510638 (-2650 4675);
PAINT SKYBLUE (-2650 4675);
DISPLAY INVISIBLE (-2650 4675);
FORCEPROP 1 LAST $LOCATION R134
J 0
(-2850 4575);
DISPLAY 0.702128 (-2850 4575);
PAINT YELLOW (-2850 4575);
FORCEPROP 1 LASTPIN (-2675 4575) $PN 1
J 0
(-2663 4587);
DISPLAY 0.787234 (-2663 4587);
PAINT MONO (-2663 4587);
FORCEPROP 1 LASTPIN (-2475 4575) $PN 2
J 0
(-2513 4587);
DISPLAY 0.787234 (-2513 4587);
PAINT MONO (-2513 4587);
FORCEPROP 0 LAST CDS_LOCATION R134
J 0
(-2850 4625);
DISPLAY 0.680851 (-2850 4625);
DISPLAY INVISIBLE (-2850 4625);
FORCEPROP 0 LAST $SEC 1
J 0
(-2850 4625);
DISPLAY 0.680851 (-2850 4625);
PAINT MONO (-2850 4625);
DISPLAY INVISIBLE (-2850 4625);
FORCEPROP 0 LAST CDS_SEC 1
J 0
(-2850 4625);
DISPLAY 0.680851 (-2850 4625);
DISPLAY INVISIBLE (-2850 4625);
FORCEADD OFFPAGE..4
R 2
(-3700 4575);
FORCEPROP 2 LAST $XR0 10 
J 0
(-3921 4575);
DISPLAY 0.638298 (-3921 4575);
PAINT MONO (-3921 4575);
FORCEPROP 2 LAST CDS_LIB standard
J 0
(-3700 4575);
DISPLAY INVISIBLE (-3700 4575);
FORCEPROP 2 LAST PATH I49
J 0
(-3650 4650);
DISPLAY 0.680851 (-3650 4650);
DISPLAY INVISIBLE (-3650 4650);
FORCEPROP 1 LAST OFFPAGE TRUE
J 2
(-4025 4450);
DISPLAY 0.872340 (-4025 4450);
PAINT GREEN (-4025 4450);
DISPLAY INVISIBLE (-4025 4450);
FORCEPROP 1 LAST COMMENT_BODY TRUE
J 2
(-3675 4475);
DISPLAY 0.872340 (-3675 4475);
PAINT PEACH (-3675 4475);
DISPLAY INVISIBLE (-3675 4475);
FORCEADD Q_RES..2
(-2750 3700);
FORCEPROP 1 LAST PART_NUMBER CS31002FB08
J 0
(-2710 3575);
DISPLAY 0.510638 (-2710 3575);
PAINT WHITE (-2710 3575);
FORCEPROP 1 LAST VALUE 10K
J 0
(-2705 3775);
DISPLAY 0.510638 (-2705 3775);
PAINT SKYBLUE (-2705 3775);
FORCEPROP 1 LAST MATERIAL CHIP
J 0
(-2710 3625);
DISPLAY 0.510638 (-2710 3625);
PAINT SKYBLUE (-2710 3625);
FORCEPROP 1 LAST WATTAGE 1/16W
J 0
(-2710 3675);
DISPLAY 0.510638 (-2710 3675);
PAINT SKYBLUE (-2710 3675);
FORCEPROP 1 LAST TOLERANCE 1%
J 0
(-2705 3725);
DISPLAY 0.510638 (-2705 3725);
PAINT SKYBLUE (-2705 3725);
FORCEPROP 1 LAST PACK_TYPE 0402LF
J 0
(-2710 3525);
DISPLAY 0.510638 (-2710 3525);
PAINT SKYBLUE (-2710 3525);
FORCEPROP 2 LAST CDS_LIB pure_quanta
J 0
(-2750 3700);
DISPLAY INVISIBLE (-2750 3700);
FORCEPROP 1 LAST PATH I50
J 0
(-2700 3875);
DISPLAY 0.978723 (-2700 3875);
PAINT WHITE (-2700 3875);
DISPLAY INVISIBLE (-2700 3875);
FORCEPROP 1 LAST $LOCATION R288
J 0
(-2705 3825);
DISPLAY 0.702128 (-2705 3825);
PAINT YELLOW (-2705 3825);
FORCEPROP 0 LAST CDS_LOCATION R288
J 0
(-2700 3875);
DISPLAY 0.680851 (-2700 3875);
DISPLAY INVISIBLE (-2700 3875);
FORCEPROP 0 LAST $SEC 1
J 0
(-2700 3875);
DISPLAY INVISIBLE (-2700 3875);
FORCEPROP 0 LAST CDS_SEC 1
J 0
(-2700 3875);
DISPLAY 0.680851 (-2700 3875);
DISPLAY INVISIBLE (-2700 3875);
FORCEPROP 1 LASTPIN (-2750 3800) $PN 1
J 0
(-2745 3762);
DISPLAY 0.808511 (-2745 3762);
PAINT WHITE (-2745 3762);
DISPLAY INVISIBLE (-2745 3762);
FORCEPROP 1 LASTPIN (-2750 3600) $PN 2
J 0
(-2745 3610);
DISPLAY 0.808511 (-2745 3610);
PAINT WHITE (-2745 3610);
DISPLAY INVISIBLE (-2745 3610);
FORCEADD UNIVERSAL_POWER..1
(-2750 3875);
FORCEPROP 3 LASTPIN (-2750 3825) SIG_NAME VCCIO2\g
J 0
(-2740 3835);
DISPLAY 0.659574 (-2740 3835);
PAINT MONO (-2740 3835);
DISPLAY INVISIBLE (-2740 3835);
FORCEPROP 1 LAST HDL_POWER VCCIO2
J 1
(-2750 3925);
DISPLAY 0.702128 (-2750 3925);
PAINT GREEN (-2750 3925);
FORCEPROP 2 LAST CDS_LIB logical_power
J 0
(-2750 3875);
DISPLAY INVISIBLE (-2750 3875);
FORCEPROP 1 LAST PATH I51
J 0
(-2700 3900);
DISPLAY 0.872340 (-2700 3900);
PAINT AQUA (-2700 3900);
DISPLAY INVISIBLE (-2700 3900);
FORCEADD OFFPAGE..1
R 2
(-2375 4150);
FORCEPROP 2 LAST $XR0 34 
J 0
(-2189 4150);
DISPLAY 0.638298 (-2189 4150);
PAINT MONO (-2189 4150);
FORCEPROP 1 LAST COMMENT_BODY TRUE
J 2
(-2500 4050);
DISPLAY 0.872340 (-2500 4050);
PAINT PEACH (-2500 4050);
DISPLAY INVISIBLE (-2500 4050);
FORCEPROP 1 LAST OFFPAGE TRUE
J 2
(-2700 4025);
DISPLAY 0.872340 (-2700 4025);
PAINT GREEN (-2700 4025);
DISPLAY INVISIBLE (-2700 4025);
FORCEPROP 2 LAST CDS_LIB standard
J 2
(-2375 4150);
DISPLAY INVISIBLE (-2375 4150);
FORCEPROP 2 LAST PATH I52
J 0
(-2175 4200);
DISPLAY 0.680851 (-2175 4200);
DISPLAY INVISIBLE (-2175 4200);
FORCEADD OFFPAGE..1
R 2
(-875 4225);
FORCEPROP 2 LAST $XR3 35 
J 0
(-419 4225);
DISPLAY 0.638298 (-419 4225);
PAINT MONO (-419 4225);
FORCEPROP 2 LAST $XR2 10 
J 0
(-509 4225);
DISPLAY 0.638298 (-509 4225);
PAINT MONO (-509 4225);
FORCEPROP 2 LAST $XR1 13 
J 0
(-599 4225);
DISPLAY 0.638298 (-599 4225);
PAINT MONO (-599 4225);
FORCEPROP 2 LAST $XR0 11 
J 0
(-689 4225);
DISPLAY 0.638298 (-689 4225);
PAINT MONO (-689 4225);
FORCEPROP 2 LAST PATH I54
J 0
(-400 4275);
DISPLAY 0.680851 (-400 4275);
DISPLAY INVISIBLE (-400 4275);
FORCEPROP 1 LAST COMMENT_BODY TRUE
J 2
(-1000 4125);
DISPLAY 0.872340 (-1000 4125);
PAINT PEACH (-1000 4125);
DISPLAY INVISIBLE (-1000 4125);
FORCEPROP 1 LAST OFFPAGE TRUE
J 2
(-1200 4100);
DISPLAY 0.872340 (-1200 4100);
PAINT GREEN (-1200 4100);
DISPLAY INVISIBLE (-1200 4100);
FORCEPROP 2 LAST CDS_LIB standard
J 2
(-875 4225);
DISPLAY INVISIBLE (-875 4225);
FORCEADD OFFPAGE..6
R 2
(-1100 3375);
FORCEPROP 2 LAST $XR0 12 
J 0
(-886 3375);
DISPLAY 0.638298 (-886 3375);
PAINT MONO (-886 3375);
FORCEPROP 2 LAST $XR1 21 
J 0
(-796 3375);
DISPLAY 0.638298 (-796 3375);
PAINT MONO (-796 3375);
FORCEPROP 2 LAST $XR2 34 
J 0
(-706 3375);
DISPLAY 0.638298 (-706 3375);
PAINT MONO (-706 3375);
FORCEPROP 2 LAST $XR3 46 
J 0
(-616 3375);
DISPLAY 0.638298 (-616 3375);
PAINT MONO (-616 3375);
FORCEPROP 2 LAST CDS_LIB standard
J 2
(-1100 3375);
DISPLAY INVISIBLE (-1100 3375);
FORCEPROP 1 LAST OFFPAGE TRUE
J 2
(-1425 3250);
DISPLAY 0.872340 (-1425 3250);
DISPLAY INVISIBLE (-1425 3250);
FORCEPROP 1 LAST COMMENT_BODY TRUE
J 2
(-1200 3300);
DISPLAY 0.872340 (-1200 3300);
PAINT GREEN (-1200 3300);
DISPLAY INVISIBLE (-1200 3300);
FORCEPROP 2 LAST PATH I55
J 0
(-600 3425);
DISPLAY 0.680851 (-600 3425);
DISPLAY INVISIBLE (-600 3425);
FORCEADD OFFPAGE..1
R 2
(-1100 3425);
FORCEPROP 2 LAST $XR0 12 
J 0
(-914 3425);
DISPLAY 0.638298 (-914 3425);
PAINT MONO (-914 3425);
FORCEPROP 2 LAST $XR1 21 
J 0
(-824 3425);
DISPLAY 0.638298 (-824 3425);
PAINT MONO (-824 3425);
FORCEPROP 2 LAST $XR2 34 
J 0
(-734 3425);
DISPLAY 0.638298 (-734 3425);
PAINT MONO (-734 3425);
FORCEPROP 2 LAST $XR3 46 
J 0
(-644 3425);
DISPLAY 0.638298 (-644 3425);
PAINT MONO (-644 3425);
FORCEPROP 2 LAST CDS_LIB standard
J 2
(-1100 3425);
DISPLAY INVISIBLE (-1100 3425);
FORCEPROP 1 LAST OFFPAGE TRUE
J 2
(-1425 3300);
DISPLAY 0.872340 (-1425 3300);
DISPLAY INVISIBLE (-1425 3300);
FORCEPROP 1 LAST COMMENT_BODY TRUE
J 2
(-1225 3325);
DISPLAY 0.872340 (-1225 3325);
PAINT GREEN (-1225 3325);
DISPLAY INVISIBLE (-1225 3325);
FORCEPROP 2 LAST PATH I56
J 0
(-625 3475);
DISPLAY 0.680851 (-625 3475);
DISPLAY INVISIBLE (-625 3475);
FORCEADD Q_RES..1
(-2525 3375);
FORCEPROP 1 LAST VALUE 0
J 2
(-2375 3375);
DISPLAY 0.510638 (-2375 3375);
PAINT SKYBLUE (-2375 3375);
FORCEPROP 1 LAST MATERIAL CHIP
J 2
(-2200 3375);
DISPLAY 0.510638 (-2200 3375);
PAINT SKYBLUE (-2200 3375);
FORCEPROP 1 LAST PATH I57
J 0
(-2575 3525);
DISPLAY 0.978723 (-2575 3525);
PAINT WHITE (-2575 3525);
DISPLAY INVISIBLE (-2575 3525);
FORCEPROP 2 LAST SEC_TYPE 0402LF
J 0
(-2575 3575);
DISPLAY 1.021277 (-2575 3575);
DISPLAY INVISIBLE (-2575 3575);
FORCEPROP 2 LAST CDS_LIB pure_quanta
J 0
(-2525 3375);
DISPLAY INVISIBLE (-2525 3375);
FORCEPROP 1 LAST TOLERANCE 5%
J 0
(-2600 3475);
DISPLAY 0.510638 (-2600 3475);
PAINT SKYBLUE (-2600 3475);
DISPLAY INVISIBLE (-2600 3475);
FORCEPROP 1 LAST WATTAGE 1/16W
J 2
(-2175 3475);
DISPLAY 0.510638 (-2175 3475);
PAINT SKYBLUE (-2175 3475);
DISPLAY INVISIBLE (-2175 3475);
FORCEPROP 1 LAST PACK_TYPE 0402LF
J 0
(-2550 3425);
DISPLAY 0.510638 (-2550 3425);
PAINT SKYBLUE (-2550 3425);
DISPLAY INVISIBLE (-2550 3425);
FORCEPROP 1 LAST PART_NUMBER CS00002JB13
J 0
(-2625 3450);
DISPLAY 0.510638 (-2625 3450);
PAINT WHITE (-2625 3450);
DISPLAY INVISIBLE (-2625 3450);
FORCEPROP 1 LAST $LOCATION R114
J 0
(-2800 3375);
DISPLAY 0.702128 (-2800 3375);
PAINT YELLOW (-2800 3375);
FORCEPROP 1 LASTPIN (-2625 3375) $PN 1
J 0
(-2613 3387);
DISPLAY 0.808511 (-2613 3387);
PAINT WHITE (-2613 3387);
FORCEPROP 1 LASTPIN (-2425 3375) $PN 2
J 0
(-2463 3387);
DISPLAY 0.808511 (-2463 3387);
PAINT WHITE (-2463 3387);
FORCEPROP 0 LAST CDS_LOCATION R114
J 0
(-2800 3425);
DISPLAY 0.680851 (-2800 3425);
DISPLAY INVISIBLE (-2800 3425);
FORCEPROP 0 LAST SEC 1
J 0
(-2675 3425);
DISPLAY 0.680851 (-2675 3425);
PAINT MONO (-2675 3425);
DISPLAY INVISIBLE (-2675 3425);
FORCEADD Q_RES..1
(-2525 3425);
FORCEPROP 1 LAST VALUE 0
J 2
(-2375 3425);
DISPLAY 0.510638 (-2375 3425);
PAINT SKYBLUE (-2375 3425);
FORCEPROP 1 LAST MATERIAL CHIP
J 2
(-2200 3425);
DISPLAY 0.510638 (-2200 3425);
PAINT SKYBLUE (-2200 3425);
FORCEPROP 1 LAST PATH I58
J 0
(-2575 3575);
DISPLAY 0.978723 (-2575 3575);
PAINT WHITE (-2575 3575);
DISPLAY INVISIBLE (-2575 3575);
FORCEPROP 2 LAST CDS_LIB pure_quanta
J 0
(-2525 3425);
DISPLAY INVISIBLE (-2525 3425);
FORCEPROP 2 LAST SEC_TYPE 0402LF
J 0
(-2575 3625);
DISPLAY 1.021277 (-2575 3625);
DISPLAY INVISIBLE (-2575 3625);
FORCEPROP 1 LAST TOLERANCE 5%
J 0
(-2600 3525);
DISPLAY 0.510638 (-2600 3525);
PAINT SKYBLUE (-2600 3525);
DISPLAY INVISIBLE (-2600 3525);
FORCEPROP 1 LAST WATTAGE 1/16W
J 2
(-2175 3525);
DISPLAY 0.510638 (-2175 3525);
PAINT SKYBLUE (-2175 3525);
DISPLAY INVISIBLE (-2175 3525);
FORCEPROP 1 LAST PACK_TYPE 0402LF
J 0
(-2550 3475);
DISPLAY 0.510638 (-2550 3475);
PAINT SKYBLUE (-2550 3475);
DISPLAY INVISIBLE (-2550 3475);
FORCEPROP 1 LAST PART_NUMBER CS00002JB13
J 0
(-2625 3500);
DISPLAY 0.510638 (-2625 3500);
PAINT WHITE (-2625 3500);
DISPLAY INVISIBLE (-2625 3500);
FORCEPROP 1 LAST $LOCATION R105
J 0
(-2800 3425);
DISPLAY 0.702128 (-2800 3425);
PAINT YELLOW (-2800 3425);
FORCEPROP 1 LASTPIN (-2625 3425) $PN 1
J 0
(-2613 3437);
DISPLAY 0.808511 (-2613 3437);
PAINT WHITE (-2613 3437);
FORCEPROP 1 LASTPIN (-2425 3425) $PN 2
J 0
(-2463 3437);
DISPLAY 0.808511 (-2463 3437);
PAINT WHITE (-2463 3437);
FORCEPROP 0 LAST CDS_LOCATION R105
J 0
(-2800 3475);
DISPLAY 0.680851 (-2800 3475);
DISPLAY INVISIBLE (-2800 3475);
FORCEPROP 0 LAST SEC 1
J 0
(-2675 3475);
DISPLAY 0.680851 (-2675 3475);
PAINT MONO (-2675 3475);
DISPLAY INVISIBLE (-2675 3475);
FORCEADD OFFPAGE..5
(-6725 4375);
FORCEPROP 2 LAST $XR1 10 
J 0
(-7069 4375);
DISPLAY 0.638298 (-7069 4375);
PAINT MONO (-7069 4375);
FORCEPROP 2 LAST $XR0 15 
J 0
(-6979 4375);
DISPLAY 0.638298 (-6979 4375);
PAINT MONO (-6979 4375);
FORCEPROP 2 LAST CDS_LIB standard
J 0
(-6725 4375);
DISPLAY INVISIBLE (-6725 4375);
FORCEPROP 1 LAST OFFPAGE TRUE
J 0
(-6400 4250);
DISPLAY 0.872340 (-6400 4250);
DISPLAY INVISIBLE (-6400 4250);
FORCEPROP 1 LAST COMMENT_BODY TRUE
J 0
(-6625 4300);
DISPLAY 0.872340 (-6625 4300);
PAINT GREEN (-6625 4300);
DISPLAY INVISIBLE (-6625 4300);
FORCEPROP 2 LAST PATH I61
J 0
(-6975 4425);
DISPLAY 0.680851 (-6975 4425);
DISPLAY INVISIBLE (-6975 4425);
FORCEADD OFFPAGE..5
(-6725 4325);
FORCEPROP 2 LAST $XR0 15 
J 0
(-6979 4325);
DISPLAY 0.638298 (-6979 4325);
PAINT MONO (-6979 4325);
FORCEPROP 2 LAST $XR1 10 
J 0
(-7069 4325);
DISPLAY 0.638298 (-7069 4325);
PAINT MONO (-7069 4325);
FORCEPROP 1 LAST COMMENT_BODY TRUE
J 0
(-6625 4250);
DISPLAY 0.872340 (-6625 4250);
PAINT GREEN (-6625 4250);
DISPLAY INVISIBLE (-6625 4250);
FORCEPROP 1 LAST OFFPAGE TRUE
J 0
(-6400 4200);
DISPLAY 0.872340 (-6400 4200);
DISPLAY INVISIBLE (-6400 4200);
FORCEPROP 2 LAST CDS_LIB standard
J 0
(-6725 4325);
DISPLAY INVISIBLE (-6725 4325);
FORCEPROP 2 LAST PATH I62
J 0
(-6975 4375);
DISPLAY 0.680851 (-6975 4375);
DISPLAY INVISIBLE (-6975 4375);
FORCEADD OFFPAGE..1
(-6725 4175);
FORCEPROP 2 LAST $XR0 15 
J 0
(-6946 4175);
DISPLAY 0.638298 (-6946 4175);
PAINT MONO (-6946 4175);
FORCEPROP 2 LAST PATH I63
J 0
(-6975 4225);
DISPLAY 0.680851 (-6975 4225);
DISPLAY INVISIBLE (-6975 4225);
FORCEPROP 1 LAST COMMENT_BODY TRUE
J 0
(-6600 4075);
DISPLAY 0.872340 (-6600 4075);
PAINT GREEN (-6600 4075);
DISPLAY INVISIBLE (-6600 4075);
FORCEPROP 1 LAST OFFPAGE TRUE
J 0
(-6400 4050);
DISPLAY 0.872340 (-6400 4050);
DISPLAY INVISIBLE (-6400 4050);
FORCEPROP 2 LAST CDS_LIB standard
J 0
(-6725 4175);
DISPLAY INVISIBLE (-6725 4175);
FORCEADD OFFPAGE..1
(-6725 4225);
FORCEPROP 2 LAST $XR0 15 
J 0
(-6946 4225);
DISPLAY 0.638298 (-6946 4225);
PAINT MONO (-6946 4225);
FORCEPROP 2 LAST PATH I64
J 0
(-6975 4275);
DISPLAY 0.680851 (-6975 4275);
DISPLAY INVISIBLE (-6975 4275);
FORCEPROP 1 LAST COMMENT_BODY TRUE
J 0
(-6600 4125);
DISPLAY 0.872340 (-6600 4125);
PAINT GREEN (-6600 4125);
DISPLAY INVISIBLE (-6600 4125);
FORCEPROP 1 LAST OFFPAGE TRUE
J 0
(-6400 4100);
DISPLAY 0.872340 (-6400 4100);
DISPLAY INVISIBLE (-6400 4100);
FORCEPROP 2 LAST CDS_LIB standard
J 0
(-6725 4225);
DISPLAY INVISIBLE (-6725 4225);
FORCEADD OFFPAGE..1
(-6725 4075);
FORCEPROP 2 LAST $XR0 13 
J 0
(-6946 4075);
DISPLAY 0.638298 (-6946 4075);
PAINT MONO (-6946 4075);
FORCEPROP 2 LAST PATH I65
J 0
(-6975 4125);
DISPLAY 0.680851 (-6975 4125);
DISPLAY INVISIBLE (-6975 4125);
FORCEPROP 2 LAST CDS_LIB standard
J 0
(-6725 4075);
DISPLAY INVISIBLE (-6725 4075);
FORCEPROP 1 LAST OFFPAGE TRUE
J 0
(-6400 3950);
DISPLAY 0.872340 (-6400 3950);
DISPLAY INVISIBLE (-6400 3950);
FORCEPROP 1 LAST COMMENT_BODY TRUE
J 0
(-6600 3975);
DISPLAY 0.872340 (-6600 3975);
PAINT GREEN (-6600 3975);
DISPLAY INVISIBLE (-6600 3975);
FORCEADD OFFPAGE..1
(-6725 4025);
FORCEPROP 2 LAST $XR0 13 
J 0
(-6946 4025);
DISPLAY 0.638298 (-6946 4025);
PAINT MONO (-6946 4025);
FORCEPROP 2 LAST PATH I66
J 0
(-6975 4075);
DISPLAY 0.680851 (-6975 4075);
DISPLAY INVISIBLE (-6975 4075);
FORCEPROP 2 LAST CDS_LIB standard
J 0
(-6725 4025);
DISPLAY INVISIBLE (-6725 4025);
FORCEPROP 1 LAST OFFPAGE TRUE
J 0
(-6400 3900);
DISPLAY 0.872340 (-6400 3900);
DISPLAY INVISIBLE (-6400 3900);
FORCEPROP 1 LAST COMMENT_BODY TRUE
J 0
(-6600 3925);
DISPLAY 0.872340 (-6600 3925);
PAINT GREEN (-6600 3925);
DISPLAY INVISIBLE (-6600 3925);
FORCEADD OFFPAGE..1
(-6725 3925);
FORCEPROP 2 LAST $XR0 13 
J 0
(-6946 3925);
DISPLAY 0.638298 (-6946 3925);
PAINT MONO (-6946 3925);
FORCEPROP 2 LAST PATH I67
J 0
(-6975 3975);
DISPLAY 0.680851 (-6975 3975);
DISPLAY INVISIBLE (-6975 3975);
FORCEPROP 2 LAST CDS_LIB standard
J 0
(-6725 3925);
DISPLAY INVISIBLE (-6725 3925);
FORCEPROP 1 LAST OFFPAGE TRUE
J 0
(-6400 3800);
DISPLAY 0.872340 (-6400 3800);
DISPLAY INVISIBLE (-6400 3800);
FORCEPROP 1 LAST COMMENT_BODY TRUE
J 0
(-6600 3825);
DISPLAY 0.872340 (-6600 3825);
PAINT GREEN (-6600 3825);
DISPLAY INVISIBLE (-6600 3825);
FORCEADD OFFPAGE..1
(-6725 3875);
FORCEPROP 2 LAST $XR0 12 
J 0
(-6946 3875);
DISPLAY 0.638298 (-6946 3875);
PAINT MONO (-6946 3875);
FORCEPROP 2 LAST PATH I68
J 0
(-6975 3925);
DISPLAY 0.680851 (-6975 3925);
DISPLAY INVISIBLE (-6975 3925);
FORCEPROP 2 LAST CDS_LIB standard
J 0
(-6725 3875);
DISPLAY INVISIBLE (-6725 3875);
FORCEPROP 1 LAST OFFPAGE TRUE
J 0
(-6400 3750);
DISPLAY 0.872340 (-6400 3750);
DISPLAY INVISIBLE (-6400 3750);
FORCEPROP 1 LAST COMMENT_BODY TRUE
J 0
(-6600 3775);
DISPLAY 0.872340 (-6600 3775);
PAINT GREEN (-6600 3775);
DISPLAY INVISIBLE (-6600 3775);
FORCEADD OFFPAGE..1
(-6725 3725);
FORCEPROP 2 LAST $XR0 12 
J 0
(-6946 3725);
DISPLAY 0.638298 (-6946 3725);
PAINT MONO (-6946 3725);
FORCEPROP 1 LAST COMMENT_BODY TRUE
J 0
(-6600 3625);
DISPLAY 0.872340 (-6600 3625);
PAINT GREEN (-6600 3625);
DISPLAY INVISIBLE (-6600 3625);
FORCEPROP 1 LAST OFFPAGE TRUE
J 0
(-6400 3600);
DISPLAY 0.872340 (-6400 3600);
DISPLAY INVISIBLE (-6400 3600);
FORCEPROP 2 LAST CDS_LIB standard
J 0
(-6725 3725);
DISPLAY INVISIBLE (-6725 3725);
FORCEPROP 2 LAST PATH I69
J 0
(-6975 3775);
DISPLAY 0.680851 (-6975 3775);
DISPLAY INVISIBLE (-6975 3775);
FORCEADD Q_RES..1
(-7250 4975);
FORCEPROP 1 LAST VALUE 0
J 2
(-7100 4975);
DISPLAY 0.510638 (-7100 4975);
PAINT SKYBLUE (-7100 4975);
FORCEPROP 1 LAST MATERIAL CHIP
J 0
(-7050 4975);
DISPLAY 0.510638 (-7050 4975);
PAINT SKYBLUE (-7050 4975);
FORCEPROP 1 LAST PATH I7
J 0
(-7300 5125);
DISPLAY 0.978723 (-7300 5125);
PAINT WHITE (-7300 5125);
DISPLAY INVISIBLE (-7300 5125);
FORCEPROP 1 LAST PART_NUMBER CS00002JB13
J 0
(-7350 5050);
DISPLAY 0.510638 (-7350 5050);
PAINT WHITE (-7350 5050);
DISPLAY INVISIBLE (-7350 5050);
FORCEPROP 1 LAST PACK_TYPE 0402LF
J 0
(-7275 5025);
DISPLAY 0.510638 (-7275 5025);
PAINT SKYBLUE (-7275 5025);
DISPLAY INVISIBLE (-7275 5025);
FORCEPROP 1 LAST WATTAGE 1/16W
J 2
(-6900 5075);
DISPLAY 0.510638 (-6900 5075);
PAINT SKYBLUE (-6900 5075);
DISPLAY INVISIBLE (-6900 5075);
FORCEPROP 1 LAST TOLERANCE 5%
J 0
(-7325 5075);
DISPLAY 0.510638 (-7325 5075);
PAINT SKYBLUE (-7325 5075);
DISPLAY INVISIBLE (-7325 5075);
FORCEPROP 2 LAST CDS_LIB pure_quanta
J 0
(-7250 4975);
DISPLAY INVISIBLE (-7250 4975);
FORCEPROP 2 LAST SEC_TYPE 0402LF
J 0
(-7300 5175);
DISPLAY 0.680851 (-7300 5175);
DISPLAY INVISIBLE (-7300 5175);
FORCEPROP 1 LAST LOCATION R579
J 0
(-7525 4975);
DISPLAY 0.702128 (-7525 4975);
PAINT YELLOW (-7525 4975);
FORCEPROP 1 LASTPIN (-7350 4975) $PN 1
J 0
(-7338 4987);
DISPLAY 0.808511 (-7338 4987);
PAINT WHITE (-7338 4987);
FORCEPROP 1 LASTPIN (-7150 4975) $PN 2
J 0
(-7188 4987);
DISPLAY 0.808511 (-7188 4987);
PAINT WHITE (-7188 4987);
FORCEPROP 2 LAST SEC 1
J 0
(-7300 5175);
DISPLAY 0.680851 (-7300 5175);
PAINT MONO (-7300 5175);
DISPLAY INVISIBLE (-7300 5175);
FORCEADD OFFPAGE..1
(-6725 3575);
FORCEPROP 2 LAST $XR0 13 
J 0
(-6946 3575);
DISPLAY 0.638298 (-6946 3575);
PAINT MONO (-6946 3575);
FORCEPROP 1 LAST COMMENT_BODY TRUE
J 0
(-6600 3475);
DISPLAY 0.872340 (-6600 3475);
PAINT GREEN (-6600 3475);
DISPLAY INVISIBLE (-6600 3475);
FORCEPROP 1 LAST OFFPAGE TRUE
J 0
(-6400 3450);
DISPLAY 0.872340 (-6400 3450);
DISPLAY INVISIBLE (-6400 3450);
FORCEPROP 2 LAST CDS_LIB standard
J 0
(-6725 3575);
DISPLAY INVISIBLE (-6725 3575);
FORCEPROP 2 LAST PATH I74
J 0
(-6975 3625);
DISPLAY 0.680851 (-6975 3625);
DISPLAY INVISIBLE (-6975 3625);
FORCEADD OFFPAGE..1
(-6725 3525);
FORCEPROP 2 LAST $XR0 13 
J 0
(-6946 3525);
DISPLAY 0.638298 (-6946 3525);
PAINT MONO (-6946 3525);
FORCEPROP 2 LAST $XR1 48 
J 0
(-7036 3525);
DISPLAY 0.638298 (-7036 3525);
PAINT MONO (-7036 3525);
FORCEPROP 2 LAST PATH I75
J 0
(-6975 3575);
DISPLAY 0.680851 (-6975 3575);
DISPLAY INVISIBLE (-6975 3575);
FORCEPROP 2 LAST CDS_LIB standard
J 0
(-6725 3525);
DISPLAY INVISIBLE (-6725 3525);
FORCEPROP 1 LAST OFFPAGE TRUE
J 0
(-6400 3400);
DISPLAY 0.872340 (-6400 3400);
DISPLAY INVISIBLE (-6400 3400);
FORCEPROP 1 LAST COMMENT_BODY TRUE
J 0
(-6600 3425);
DISPLAY 0.872340 (-6600 3425);
PAINT GREEN (-6600 3425);
DISPLAY INVISIBLE (-6600 3425);
FORCEADD OFFPAGE..1
(-6725 3375);
FORCEPROP 2 LAST $XR0 13 
J 0
(-6946 3375);
DISPLAY 0.638298 (-6946 3375);
PAINT MONO (-6946 3375);
FORCEPROP 1 LAST COMMENT_BODY TRUE
J 0
(-6600 3275);
DISPLAY 0.872340 (-6600 3275);
PAINT PEACH (-6600 3275);
DISPLAY INVISIBLE (-6600 3275);
FORCEPROP 1 LAST OFFPAGE TRUE
J 0
(-6400 3250);
DISPLAY 0.872340 (-6400 3250);
PAINT GREEN (-6400 3250);
DISPLAY INVISIBLE (-6400 3250);
FORCEPROP 2 LAST CDS_LIB standard
J 0
(-6725 3375);
DISPLAY INVISIBLE (-6725 3375);
FORCEPROP 2 LAST PATH I76
J 0
(-6925 3425);
DISPLAY 0.680851 (-6925 3425);
DISPLAY INVISIBLE (-6925 3425);
FORCEADD OFFPAGE..1
(-6725 3425);
FORCEPROP 2 LAST $XR0 13 
J 0
(-6946 3425);
DISPLAY 0.638298 (-6946 3425);
PAINT MONO (-6946 3425);
FORCEPROP 1 LAST COMMENT_BODY TRUE
J 0
(-6600 3325);
DISPLAY 0.872340 (-6600 3325);
PAINT PEACH (-6600 3325);
DISPLAY INVISIBLE (-6600 3325);
FORCEPROP 1 LAST OFFPAGE TRUE
J 0
(-6400 3300);
DISPLAY 0.872340 (-6400 3300);
PAINT GREEN (-6400 3300);
DISPLAY INVISIBLE (-6400 3300);
FORCEPROP 2 LAST CDS_LIB standard
J 0
(-6725 3425);
DISPLAY INVISIBLE (-6725 3425);
FORCEPROP 2 LAST PATH I77
J 0
(-6925 3475);
DISPLAY 0.680851 (-6925 3475);
DISPLAY INVISIBLE (-6925 3475);
FORCEADD Q_RES..1
(-1900 4225);
FORCEPROP 1 LAST VALUE 0
J 2
(-1750 4225);
DISPLAY 0.510638 (-1750 4225);
PAINT SKYBLUE (-1750 4225);
FORCEPROP 1 LAST MATERIAL CHIP
J 2
(-1575 4225);
DISPLAY 0.510638 (-1575 4225);
PAINT SKYBLUE (-1575 4225);
FORCEPROP 1 LAST PART_NUMBER CS00002JB13
J 0
(-2000 4300);
DISPLAY 0.510638 (-2000 4300);
PAINT WHITE (-2000 4300);
DISPLAY INVISIBLE (-2000 4300);
FORCEPROP 1 LAST PACK_TYPE 0402LF
J 0
(-1925 4275);
DISPLAY 0.510638 (-1925 4275);
PAINT SKYBLUE (-1925 4275);
DISPLAY INVISIBLE (-1925 4275);
FORCEPROP 1 LAST WATTAGE 1/16W
J 2
(-1550 4325);
DISPLAY 0.510638 (-1550 4325);
PAINT SKYBLUE (-1550 4325);
DISPLAY INVISIBLE (-1550 4325);
FORCEPROP 1 LAST TOLERANCE 5%
J 0
(-1975 4325);
DISPLAY 0.510638 (-1975 4325);
PAINT SKYBLUE (-1975 4325);
DISPLAY INVISIBLE (-1975 4325);
FORCEPROP 1 LAST PATH I78
J 0
(-1950 4375);
DISPLAY 0.978723 (-1950 4375);
PAINT WHITE (-1950 4375);
DISPLAY INVISIBLE (-1950 4375);
FORCEPROP 2 LAST CDS_LIB pure_quanta
J 0
(-1900 4225);
DISPLAY INVISIBLE (-1900 4225);
FORCEPROP 1 LAST LOCATION R748
J 0
(-2175 4225);
DISPLAY 0.702128 (-2175 4225);
PAINT YELLOW (-2175 4225);
FORCEPROP 1 LASTPIN (-2000 4225) $PN 1
J 0
(-1988 4237);
DISPLAY 0.787234 (-1988 4237);
PAINT MONO (-1988 4237);
FORCEPROP 1 LASTPIN (-1800 4225) $PN 2
J 0
(-1838 4237);
DISPLAY 0.787234 (-1838 4237);
PAINT MONO (-1838 4237);
FORCEPROP 0 LAST $SEC 1
J 0
(-2175 4275);
DISPLAY 0.680851 (-2175 4275);
PAINT MONO (-2175 4275);
DISPLAY INVISIBLE (-2175 4275);
FORCEPROP 0 LAST CDS_SEC 1
J 0
(-2175 4275);
DISPLAY 0.680851 (-2175 4275);
DISPLAY INVISIBLE (-2175 4275);
FORCEADD OFFPAGE..4
R 2
(-3700 4525);
FORCEPROP 1 LAST COMMENT_BODY TRUE
J 2
(-3675 4425);
DISPLAY 0.872340 (-3675 4425);
PAINT PEACH (-3675 4425);
DISPLAY INVISIBLE (-3675 4425);
FORCEPROP 1 LAST OFFPAGE TRUE
J 2
(-4025 4400);
DISPLAY 0.872340 (-4025 4400);
PAINT GREEN (-4025 4400);
DISPLAY INVISIBLE (-4025 4400);
FORCEPROP 2 LAST PATH I79
J 0
(-3650 4600);
DISPLAY 0.680851 (-3650 4600);
DISPLAY INVISIBLE (-3650 4600);
FORCEPROP 2 LAST CDS_LIB standard
J 0
(-3700 4525);
DISPLAY INVISIBLE (-3700 4525);
FORCEADD Q_RES..1
(-7250 5075);
FORCEPROP 1 LAST VALUE 0
J 2
(-7100 5075);
DISPLAY 0.510638 (-7100 5075);
PAINT SKYBLUE (-7100 5075);
FORCEPROP 1 LAST MATERIAL CHIP
J 0
(-7050 5075);
DISPLAY 0.510638 (-7050 5075);
PAINT SKYBLUE (-7050 5075);
FORCEPROP 1 LAST PATH I8
J 0
(-7300 5225);
DISPLAY 0.978723 (-7300 5225);
PAINT WHITE (-7300 5225);
DISPLAY INVISIBLE (-7300 5225);
FORCEPROP 1 LAST PART_NUMBER CS00002JB13
J 0
(-7350 5150);
DISPLAY 0.510638 (-7350 5150);
PAINT WHITE (-7350 5150);
DISPLAY INVISIBLE (-7350 5150);
FORCEPROP 1 LAST PACK_TYPE 0402LF
J 0
(-7275 5125);
DISPLAY 0.510638 (-7275 5125);
PAINT SKYBLUE (-7275 5125);
DISPLAY INVISIBLE (-7275 5125);
FORCEPROP 1 LAST WATTAGE 1/16W
J 2
(-6900 5175);
DISPLAY 0.510638 (-6900 5175);
PAINT SKYBLUE (-6900 5175);
DISPLAY INVISIBLE (-6900 5175);
FORCEPROP 1 LAST TOLERANCE 5%
J 0
(-7325 5175);
DISPLAY 0.510638 (-7325 5175);
PAINT SKYBLUE (-7325 5175);
DISPLAY INVISIBLE (-7325 5175);
FORCEPROP 2 LAST CDS_LIB pure_quanta
J 0
(-7250 5075);
DISPLAY INVISIBLE (-7250 5075);
FORCEPROP 2 LAST SEC_TYPE 0402LF
J 0
(-7300 5275);
DISPLAY 0.680851 (-7300 5275);
DISPLAY INVISIBLE (-7300 5275);
FORCEPROP 1 LAST LOCATION R578
J 0
(-7525 5075);
DISPLAY 0.702128 (-7525 5075);
PAINT YELLOW (-7525 5075);
FORCEPROP 1 LASTPIN (-7350 5075) $PN 1
J 0
(-7338 5087);
DISPLAY 0.808511 (-7338 5087);
PAINT WHITE (-7338 5087);
FORCEPROP 1 LASTPIN (-7150 5075) $PN 2
J 0
(-7188 5087);
DISPLAY 0.808511 (-7188 5087);
PAINT WHITE (-7188 5087);
FORCEPROP 2 LAST SEC 1
J 0
(-7300 5275);
DISPLAY 0.680851 (-7300 5275);
PAINT MONO (-7300 5275);
DISPLAY INVISIBLE (-7300 5275);
FORCEADD Q_RES..1
(-7250 4825);
FORCEPROP 1 LAST VALUE 33.2
J 2
(-7025 4825);
DISPLAY 0.510638 (-7025 4825);
PAINT SKYBLUE (-7025 4825);
FORCEPROP 1 LAST MATERIAL CHIP
J 0
(-7000 4825);
DISPLAY 0.510638 (-7000 4825);
PAINT SKYBLUE (-7000 4825);
FORCEPROP 1 LAST TOLERANCE 1%
J 0
(-7225 4775);
DISPLAY 0.510638 (-7225 4775);
PAINT SKYBLUE (-7225 4775);
DISPLAY INVISIBLE (-7225 4775);
FORCEPROP 1 LAST PART_NUMBER CS03322FB03
J 0
(-7325 4700);
DISPLAY 0.510638 (-7325 4700);
PAINT WHITE (-7325 4700);
DISPLAY INVISIBLE (-7325 4700);
FORCEPROP 1 LAST WATTAGE 1/16W
J 2
(-7125 4750);
DISPLAY 0.510638 (-7125 4750);
PAINT SKYBLUE (-7125 4750);
DISPLAY INVISIBLE (-7125 4750);
FORCEPROP 1 LAST PACK_TYPE 0402LF
J 0
(-7250 4725);
DISPLAY 0.510638 (-7250 4725);
PAINT SKYBLUE (-7250 4725);
DISPLAY INVISIBLE (-7250 4725);
FORCEPROP 1 LAST PATH I80
J 0
(-7300 4975);
DISPLAY 0.978723 (-7300 4975);
PAINT WHITE (-7300 4975);
DISPLAY INVISIBLE (-7300 4975);
FORCEPROP 2 LAST CDS_LIB pure_quanta
J 0
(-7250 4825);
DISPLAY INVISIBLE (-7250 4825);
FORCEPROP 1 LAST LOCATION R635
J 0
(-7475 4825);
DISPLAY 0.702128 (-7475 4825);
PAINT YELLOW (-7475 4825);
FORCEPROP 1 LASTPIN (-7350 4825) $PN 1
J 0
(-7338 4837);
DISPLAY 0.787234 (-7338 4837);
PAINT MONO (-7338 4837);
FORCEPROP 1 LASTPIN (-7150 4825) $PN 2
J 0
(-7188 4837);
DISPLAY 0.787234 (-7188 4837);
PAINT MONO (-7188 4837);
FORCEPROP 0 LAST $SEC 1
J 0
(-7475 4875);
DISPLAY 0.680851 (-7475 4875);
PAINT MONO (-7475 4875);
DISPLAY INVISIBLE (-7475 4875);
FORCEPROP 0 LAST CDS_SEC 1
J 0
(-7475 4875);
DISPLAY 0.680851 (-7475 4875);
DISPLAY INVISIBLE (-7475 4875);
FORCEADD Q_RES..1
(-7250 4775);
FORCEPROP 1 LAST VALUE 33.2
J 2
(-7025 4775);
DISPLAY 0.510638 (-7025 4775);
PAINT SKYBLUE (-7025 4775);
FORCEPROP 1 LAST MATERIAL CHIP
J 0
(-7000 4775);
DISPLAY 0.510638 (-7000 4775);
PAINT SKYBLUE (-7000 4775);
FORCEPROP 1 LAST TOLERANCE 1%
J 0
(-7225 4725);
DISPLAY 0.510638 (-7225 4725);
PAINT SKYBLUE (-7225 4725);
DISPLAY INVISIBLE (-7225 4725);
FORCEPROP 1 LAST PART_NUMBER CS03322FB03
J 0
(-7325 4650);
DISPLAY 0.510638 (-7325 4650);
PAINT WHITE (-7325 4650);
DISPLAY INVISIBLE (-7325 4650);
FORCEPROP 1 LAST WATTAGE 1/16W
J 2
(-7125 4700);
DISPLAY 0.510638 (-7125 4700);
PAINT SKYBLUE (-7125 4700);
DISPLAY INVISIBLE (-7125 4700);
FORCEPROP 1 LAST PACK_TYPE 0402LF
J 0
(-7250 4675);
DISPLAY 0.510638 (-7250 4675);
PAINT SKYBLUE (-7250 4675);
DISPLAY INVISIBLE (-7250 4675);
FORCEPROP 1 LAST PATH I81
J 0
(-7300 4925);
DISPLAY 0.978723 (-7300 4925);
PAINT WHITE (-7300 4925);
DISPLAY INVISIBLE (-7300 4925);
FORCEPROP 2 LAST CDS_LIB pure_quanta
J 0
(-7250 4775);
DISPLAY INVISIBLE (-7250 4775);
FORCEPROP 1 LAST LOCATION R445
J 0
(-7475 4775);
DISPLAY 0.702128 (-7475 4775);
PAINT YELLOW (-7475 4775);
FORCEPROP 1 LASTPIN (-7350 4775) $PN 1
J 0
(-7338 4787);
DISPLAY 0.787234 (-7338 4787);
PAINT MONO (-7338 4787);
FORCEPROP 1 LASTPIN (-7150 4775) $PN 2
J 0
(-7188 4787);
DISPLAY 0.787234 (-7188 4787);
PAINT MONO (-7188 4787);
FORCEPROP 0 LAST $SEC 1
J 0
(-7475 4825);
DISPLAY 0.680851 (-7475 4825);
PAINT MONO (-7475 4825);
DISPLAY INVISIBLE (-7475 4825);
FORCEPROP 0 LAST CDS_SEC 1
J 0
(-7475 4825);
DISPLAY 0.680851 (-7475 4825);
DISPLAY INVISIBLE (-7475 4825);
FORCEADD Q_RES..1
(-7250 4525);
FORCEPROP 1 LAST VALUE 33.2
J 2
(-7025 4525);
DISPLAY 0.510638 (-7025 4525);
PAINT SKYBLUE (-7025 4525);
FORCEPROP 1 LAST MATERIAL CHIP
J 0
(-7000 4525);
DISPLAY 0.510638 (-7000 4525);
PAINT SKYBLUE (-7000 4525);
FORCEPROP 1 LAST TOLERANCE 1%
J 0
(-7225 4475);
DISPLAY 0.510638 (-7225 4475);
PAINT SKYBLUE (-7225 4475);
DISPLAY INVISIBLE (-7225 4475);
FORCEPROP 1 LAST PART_NUMBER CS03322FB03
J 0
(-7325 4400);
DISPLAY 0.510638 (-7325 4400);
PAINT WHITE (-7325 4400);
DISPLAY INVISIBLE (-7325 4400);
FORCEPROP 1 LAST WATTAGE 1/16W
J 2
(-7125 4450);
DISPLAY 0.510638 (-7125 4450);
PAINT SKYBLUE (-7125 4450);
DISPLAY INVISIBLE (-7125 4450);
FORCEPROP 1 LAST PACK_TYPE 0402LF
J 0
(-7250 4425);
DISPLAY 0.510638 (-7250 4425);
PAINT SKYBLUE (-7250 4425);
DISPLAY INVISIBLE (-7250 4425);
FORCEPROP 1 LAST PATH I82
J 0
(-7300 4675);
DISPLAY 0.978723 (-7300 4675);
PAINT WHITE (-7300 4675);
DISPLAY INVISIBLE (-7300 4675);
FORCEPROP 2 LAST CDS_LIB pure_quanta
J 0
(-7250 4525);
DISPLAY INVISIBLE (-7250 4525);
FORCEPROP 1 LAST LOCATION R750
J 0
(-7475 4525);
DISPLAY 0.702128 (-7475 4525);
PAINT YELLOW (-7475 4525);
FORCEPROP 1 LASTPIN (-7350 4525) $PN 1
J 0
(-7338 4537);
DISPLAY 0.787234 (-7338 4537);
PAINT MONO (-7338 4537);
FORCEPROP 1 LASTPIN (-7150 4525) $PN 2
J 0
(-7188 4537);
DISPLAY 0.787234 (-7188 4537);
PAINT MONO (-7188 4537);
FORCEPROP 0 LAST $SEC 1
J 0
(-7475 4575);
DISPLAY 0.680851 (-7475 4575);
PAINT MONO (-7475 4575);
DISPLAY INVISIBLE (-7475 4575);
FORCEPROP 0 LAST CDS_SEC 1
J 0
(-7475 4575);
DISPLAY 0.680851 (-7475 4575);
DISPLAY INVISIBLE (-7475 4575);
FORCEADD Q_RES..1
(-7250 4625);
FORCEPROP 1 LAST VALUE 0
J 2
(-7100 4625);
DISPLAY 0.510638 (-7100 4625);
PAINT SKYBLUE (-7100 4625);
FORCEPROP 1 LAST MATERIAL CHIP
J 0
(-7050 4625);
DISPLAY 0.510638 (-7050 4625);
PAINT SKYBLUE (-7050 4625);
FORCEPROP 1 LAST PATH I9
J 0
(-7300 4775);
DISPLAY 0.978723 (-7300 4775);
PAINT WHITE (-7300 4775);
DISPLAY INVISIBLE (-7300 4775);
FORCEPROP 1 LAST PART_NUMBER CS00002JB13
J 0
(-7350 4700);
DISPLAY 0.510638 (-7350 4700);
PAINT WHITE (-7350 4700);
DISPLAY INVISIBLE (-7350 4700);
FORCEPROP 1 LAST PACK_TYPE 0402LF
J 0
(-7275 4675);
DISPLAY 0.510638 (-7275 4675);
PAINT SKYBLUE (-7275 4675);
DISPLAY INVISIBLE (-7275 4675);
FORCEPROP 1 LAST WATTAGE 1/16W
J 2
(-6900 4725);
DISPLAY 0.510638 (-6900 4725);
PAINT SKYBLUE (-6900 4725);
DISPLAY INVISIBLE (-6900 4725);
FORCEPROP 1 LAST TOLERANCE 5%
J 0
(-7325 4725);
DISPLAY 0.510638 (-7325 4725);
PAINT SKYBLUE (-7325 4725);
DISPLAY INVISIBLE (-7325 4725);
FORCEPROP 2 LAST SEC_TYPE 0402LF
J 0
(-7300 4825);
DISPLAY 0.680851 (-7300 4825);
DISPLAY INVISIBLE (-7300 4825);
FORCEPROP 2 LAST CDS_LIB pure_quanta
J 0
(-7250 4625);
DISPLAY INVISIBLE (-7250 4625);
FORCEPROP 1 LAST LOCATION R747
J 0
(-7525 4625);
DISPLAY 0.702128 (-7525 4625);
PAINT YELLOW (-7525 4625);
FORCEPROP 1 LASTPIN (-7350 4625) $PN 1
J 0
(-7338 4637);
DISPLAY 0.808511 (-7338 4637);
PAINT WHITE (-7338 4637);
FORCEPROP 1 LASTPIN (-7150 4625) $PN 2
J 0
(-7188 4637);
DISPLAY 0.808511 (-7188 4637);
PAINT WHITE (-7188 4637);
FORCEPROP 2 LAST SEC 1
J 0
(-7300 4825);
DISPLAY 0.680851 (-7300 4825);
PAINT MONO (-7300 4825);
DISPLAY INVISIBLE (-7300 4825);
FORCEADD QUANTA_TITLE_BLOCK_C..1
(0 0);
FORCEPROP 0 LAST CDS_CON_LAST_MODIFIED Fri Aug 25 17:25:44 2023
J 0
(-1885 15);
DISPLAY INVISIBLE (-1885 15);
FORCEPROP 2 LAST Q_DEPT 
J 1
(-3763 49);
DISPLAY 1.957447 (-3763 49);
PAINT GREEN (-3763 49);
FORCEPROP 1 LAST CUSTOM_TXT_CDS <CON_LAST_MODIFIED>
J 0
(-1885 15);
DISPLAY 0.978723 (-1885 15);
FORCEPROP 2 LAST CUSTOM_TXT_CDS <XR_PAGE_TITLE>
J 0
(-7890 5250);
DISPLAY 0.638298 (-7890 5250);
PAINT PINK (-7890 5250);
DISPLAY INVISIBLE (-7890 5250);
FORCEPROP 1 LAST CUSTOM_TXT_CDS <NAME_2>
J 0
(-3175 50);
FORCEPROP 1 LAST CUSTOM_TXT_CDS <NAME_1>
J 0
(-3175 175);
FORCEPROP 1 LAST CUSTOM_TXT_CDS <Q_NUMBER>
J 0
(-1403 103);
DISPLAY 1.212766 (-1403 103);
FORCEPROP 1 LAST CUSTOM_TXT_CDS <Q_PROJ>
J 0
(-2382 102);
DISPLAY 1.212766 (-2382 102);
FORCEPROP 1 LAST CUSTOM_TXT_CDS <Q_REV>
J 0
(-184 103);
DISPLAY 1.212766 (-184 103);
FORCEPROP 1 LAST CUSTOM_TXT_CDS <CON_PAGE_NUM> OF <CON_TOTAL_PAGES>
J 0
(-446 18);
DISPLAY 0.978723 (-446 18);
FORCEPROP 1 LAST Q_TITLE FPGA 3/8
J 0
(-9366 26);
DISPLAY 2.446809 (-9366 26);
PAINT GREEN (-9366 26);
FORCEPROP 2 LAST CDS_XR_PAGE_TITLE CR-36 : @SCM_LIB.SCM(SCH_1):PAGE36
J 0
(-7890 5250);
DISPLAY 0.638298 (-7890 5250);
PAINT PINK (-7890 5250);
DISPLAY INVISIBLE (-7890 5250);
FORCEPROP 2 LAST CDS_LIB pure_quanta
J 0
(0 0);
DISPLAY INVISIBLE (0 0);
FORCEPROP 1 LAST COMMENT_BODY TRUE
J 0
(12 -13);
DISPLAY 0.978723 (12 -13);
PAINT GREEN (12 -13);
DISPLAY INVISIBLE (12 -13);
FORCEPROP 1 LAST CDS_LMAN_SYM_OUTLINE -9475,6775,100,-125
J 0
(0 0);
DISPLAY 0.468085 (0 0);
PAINT GREEN (0 0);
DISPLAY INVISIBLE (0 0);
FORCEPROP 2 LAST PAGE_BORDER TRUE
J 0
(-7890 5250);
DISPLAY 0.638298 (-7890 5250);
PAINT PINK (-7890 5250);
DISPLAY INVISIBLE (-7890 5250);
WIRE 16 -1 (-3650 3125)(-3650 3075);
WIRE 16 -1 (-2750 3800)(-2750 3825);
WIRE 16 -1 (-5950 3125)(-5950 3075);
WIRE 16 -1 (-5950 3075)(-5775 3075);
WIRE 16 -1 (-5775 3075)(-5575 3075);
WIRE 16 -1 (-5775 3025)(-5575 3025);
WIRE 16 -1 (-5775 3025)(-5775 3075);
WIRE 16 -1 (-3825 3075)(-4025 3075);
WIRE 16 -1 (-3650 3075)(-3825 3075);
WIRE 16 -1 (-3825 3025)(-3825 3075);
WIRE 16 -1 (-4025 3025)(-3825 3025);
WIRE 16 -1 (-6675 4025)(-5575 4025);
FORCEPROP 2 LAST SIG_NAME IRQ_SML0_ALERT_R_N
J 0
(-6610 4035);
DISPLAY 0.851064 (-6610 4035);
WIRE 16 -1 (-6675 4075)(-5575 4075);
FORCEPROP 2 LAST SIG_NAME CLK_GEN2_BMC_RC_OE_N
J 0
(-6610 4085);
DISPLAY 0.851064 (-6610 4085);
WIRE 16 -1 (-5575 4525)(-7150 4525);
FORCEPROP 2 LAST SIG_NAME FM_BMC_DEBUG_SW_R2_N
J 0
(-6860 4535);
DISPLAY 0.851064 (-6860 4535);
WIRE 16 -1 (-5575 4625)(-7150 4625);
FORCEPROP 2 LAST SIG_NAME FM_BMC_CRASHLOG_TRIG_R2_N
J 0
(-6860 4635);
DISPLAY 0.851064 (-6860 4635);
WIRE 16 -1 (-5575 4675)(-7150 4675);
FORCEPROP 2 LAST SIG_NAME IRQ_PCH_TPM_SPI_R2_N
J 0
(-6860 4685);
DISPLAY 0.851064 (-6860 4685);
WIRE 16 -1 (-5575 4775)(-7150 4775);
FORCEPROP 2 LAST SIG_NAME FM_BMC_SUSACK_R2_N
J 2
(-6185 4785);
DISPLAY 0.808511 (-6185 4785);
WIRE 16 -1 (-5575 5075)(-7150 5075);
FORCEPROP 2 LAST SIG_NAME PWRGD_DSW_PWROK_R2
J 0
(-6860 5085);
DISPLAY 0.851064 (-6860 5085);
WIRE 16 -1 (-5575 4975)(-7150 4975);
FORCEPROP 2 LAST SIG_NAME FM_DEBUG_PORT_R2_PRSNT_N
J 0
(-6860 4985);
DISPLAY 0.851064 (-6860 4985);
WIRE 16 -1 (-5575 4925)(-6875 4925);
FORCEPROP 2 LAST SIG_NAME TP_PLD_C13
J 0
(-6860 4935);
DISPLAY 0.851064 (-6860 4935);
WIRE 16 -1 (-5575 5125)(-7150 5125);
FORCEPROP 2 LAST SIG_NAME FM_SOL_UART_CH_SEL_R2
J 0
(-6860 5135);
DISPLAY 0.851064 (-6860 5135);
WIRE 16 -1 (-5575 5275)(-7150 5275);
FORCEPROP 2 LAST SIG_NAME FM_P12V_HSC_ENABLE_R2
J 0
(-6860 5285);
DISPLAY 0.808511 (-6860 5285);
WIRE 16 -1 (-5575 4825)(-7150 4825);
FORCEPROP 2 LAST SIG_NAME RST_WDTRST_PLD_R2_N
J 0
(-6860 4835);
DISPLAY 0.851064 (-6860 4835);
WIRE 16 -1 (-6675 3725)(-5575 3725);
FORCEPROP 2 LAST SIG_NAME RST_PFR_OVR_RTC_R
J 0
(-6610 3735);
DISPLAY 0.851064 (-6610 3735);
WIRE 16 -1 (-1800 4225)(-925 4225);
FORCEPROP 2 LAST SIG_NAME RST_ROT_CPU_N
J 0
(-1460 4235);
DISPLAY 0.851064 (-1460 4235);
WIRE 16 -1 (-1150 3375)(-2425 3375);
FORCEPROP 2 LAST SIG_NAME SMB_BMC_MM16_R5_SDA
J 0
(-2085 3385);
DISPLAY 0.851064 (-2085 3385);
WIRE 16 -1 (-1150 3425)(-2425 3425);
FORCEPROP 2 LAST SIG_NAME SMB_BMC_MM16_R5_SCL
J 0
(-2085 3435);
DISPLAY 0.851064 (-2085 3435);
WIRE 16 -1 (-2475 4525)(-2200 4525);
WIRE 16 -1 (-2200 4525)(-2200 4775);
WIRE 16 -1 (-2200 4775)(-2475 4775);
WIRE 16 -1 (-1575 4775)(-2200 4775);
FORCEPROP 2 LAST SIG_NAME FM_UARTSW_MSB_N
J 0
(-2185 4785);
DISPLAY 0.851064 (-2185 4785);
WIRE 16 -1 (-2475 4825)(-2250 4825);
WIRE 16 -1 (-1575 4825)(-2250 4825);
FORCEPROP 2 LAST SIG_NAME FM_UARTSW_LSB_N
J 0
(-2185 4835);
DISPLAY 0.851064 (-2185 4835);
WIRE 16 -1 (-2250 4825)(-2250 4575);
WIRE 16 -1 (-2475 4575)(-2250 4575);
WIRE 16 -1 (-4025 4825)(-2675 4825);
FORCEPROP 2 LAST SIG_NAME FM_UARTSW_LSB_R_N
J 0
(-3585 4835);
DISPLAY 0.851064 (-3585 4835);
WIRE 16 -1 (-4025 4775)(-2675 4775);
FORCEPROP 2 LAST SIG_NAME FM_UARTSW_MSB_R_N
J 0
(-3585 4785);
DISPLAY 0.851064 (-3585 4785);
WIRE 16 -1 (-4025 5075)(-2675 5075);
FORCEPROP 2 LAST SIG_NAME PWRGD_P1V0_AUX_R1
J 0
(-3585 5085);
DISPLAY 0.851064 (-3585 5085);
WIRE 16 -1 (-4025 5125)(-2675 5125);
FORCEPROP 2 LAST SIG_NAME PWRGD_P1V2_AUX_R1
J 0
(-3585 5135);
DISPLAY 0.851064 (-3585 5135);
WIRE 16 -1 (-2475 5225)(-1575 5225);
FORCEPROP 2 LAST SIG_NAME PWRGD_P3V3_RGM
J 0
(-2185 5235);
DISPLAY 0.851064 (-2185 5235);
WIRE 16 -1 (-2475 5275)(-1575 5275);
FORCEPROP 2 LAST SIG_NAME PWRGD_P1V8_AUX
J 0
(-2185 5285);
DISPLAY 0.851064 (-2185 5285);
WIRE 16 -1 (-2475 5075)(-1575 5075);
FORCEPROP 2 LAST SIG_NAME PWRGD_P1V0_AUX
J 0
(-2185 5085);
DISPLAY 0.851064 (-2185 5085);
WIRE 16 -1 (-2475 5125)(-1575 5125);
FORCEPROP 2 LAST SIG_NAME PWRGD_P1V2_AUX
J 0
(-2185 5135);
DISPLAY 0.851064 (-2185 5135);
WIRE 16 -1 (-4025 5275)(-2675 5275);
FORCEPROP 2 LAST SIG_NAME PWRGD_P1V8_AUX_R1
J 0
(-3585 5285);
DISPLAY 0.851064 (-3585 5285);
WIRE 16 -1 (-4025 5225)(-2675 5225);
FORCEPROP 2 LAST SIG_NAME PWRGD_P3V3_RGM_R1
J 0
(-3585 5235);
DISPLAY 0.851064 (-3585 5235);
WIRE 16 -1 (-3650 4575)(-2675 4575);
FORCEPROP 2 LAST SIG_NAME FM_BMC_UARTSW_LSB_N
J 0
(-3610 4585);
DISPLAY 0.851064 (-3610 4585);
WIRE 16 -1 (-3650 4525)(-2675 4525);
FORCEPROP 2 LAST SIG_NAME FM_BMC_UARTSW_MSB_N
J 0
(-3610 4535);
DISPLAY 0.851064 (-3610 4535);
WIRE 16 -1 (-4025 4225)(-2550 4225);
WIRE 16 -1 (-2550 4225)(-2000 4225);
FORCEPROP 2 LAST SIG_NAME PU_FPGA_NCONFIG
J 2
(-2210 4235);
DISPLAY 0.808511 (-2210 4235);
WIRE 16 -1 (-2550 4150)(-2550 4225);
WIRE 16 -1 (-2425 4150)(-2550 4150);
WIRE 16 -1 (-5575 3375)(-6675 3375);
FORCEPROP 2 LAST SIG_NAME FM_BMC_CPU_FBRK_OUT_R_N
J 0
(-6610 3385);
DISPLAY 0.808511 (-6610 3385);
WIRE 16 -1 (-8450 4525)(-7350 4525);
FORCEPROP 2 LAST SIG_NAME FM_BMC_DEBUG_SW_N
J 0
(-8435 4535);
DISPLAY 0.851064 (-8435 4535);
WIRE 16 -1 (-8450 4675)(-7350 4675);
FORCEPROP 2 LAST SIG_NAME IRQ_PCH_TPM_SPI_N
J 0
(-8435 4685);
DISPLAY 0.851064 (-8435 4685);
WIRE 16 -1 (-8450 4625)(-7350 4625);
FORCEPROP 2 LAST SIG_NAME FM_BMC_CRASHLOG_TRIG_N
J 0
(-8435 4635);
DISPLAY 0.851064 (-8435 4635);
WIRE 16 -1 (-8450 4775)(-7350 4775);
FORCEPROP 2 LAST SIG_NAME FM_BMC_SUSACK_N
J 2
(-7860 4785);
DISPLAY 0.808511 (-7860 4785);
WIRE 16 -1 (-8450 4825)(-7350 4825);
FORCEPROP 2 LAST SIG_NAME RST_WDTRST_PLD_N
J 0
(-8435 4835);
DISPLAY 0.851064 (-8435 4835);
WIRE 16 -1 (-8450 4975)(-7350 4975);
FORCEPROP 2 LAST SIG_NAME FM_DEBUG_PORT_PRSNT_N
J 0
(-8460 4985);
DISPLAY 0.851064 (-8460 4985);
WIRE 16 -1 (-6725 4475)(-5575 4475);
FORCEPROP 2 LAST SIG_NAME NC_FM_PFR_NO_SERVICE_ACT_N
J 0
(-6710 4485);
DISPLAY 0.851064 (-6710 4485);
WIRE 16 -1 (-6675 4375)(-5575 4375);
FORCEPROP 2 LAST SIG_NAME FM_HDD_LED_N
J 0
(-6610 4385);
DISPLAY 0.851064 (-6610 4385);
WIRE 16 -1 (-6675 4325)(-5575 4325);
FORCEPROP 2 LAST SIG_NAME FM_PCH_BEEP_LED
J 0
(-6610 4335);
DISPLAY 0.851064 (-6610 4335);
WIRE 16 -1 (-6675 4225)(-5575 4225);
FORCEPROP 2 LAST SIG_NAME GPU_NVS_PWR_BRAKE_R_N
J 0
(-6610 4235);
DISPLAY 0.851064 (-6610 4235);
WIRE 16 -1 (-6675 4175)(-5575 4175);
FORCEPROP 2 LAST SIG_NAME GPU_WP_HW_CTRL_R_N
J 0
(-6610 4185);
DISPLAY 0.851064 (-6610 4185);
WIRE 16 -1 (-6675 3925)(-5575 3925);
FORCEPROP 2 LAST SIG_NAME BMC_MONITER
J 0
(-6610 3935);
DISPLAY 0.851064 (-6610 3935);
WIRE 16 -1 (-6675 3875)(-5575 3875);
FORCEPROP 2 LAST SIG_NAME FM_PFR_DSW_PWROK_N
J 0
(-6610 3885);
DISPLAY 0.851064 (-6610 3885);
WIRE 16 -1 (-6675 3675)(-5575 3675);
FORCEPROP 2 LAST SIG_NAME NC_FM_PFR_UPDATE_N
J 0
(-6610 3685);
DISPLAY 0.851064 (-6610 3685);
WIRE 16 -1 (-6675 3525)(-5575 3525);
FORCEPROP 2 LAST SIG_NAME FM_JTAG_TCK_MUX_BMC_SEL
J 0
(-6610 3535);
DISPLAY 0.851064 (-6610 3535);
WIRE 16 -1 (-2750 3575)(-2750 3600);
WIRE 16 -1 (-4025 3575)(-2750 3575);
FORCEPROP 2 LAST SIG_NAME PU_PB25A
J 0
(-3387 3585);
DISPLAY 0.851064 (-3387 3585);
WIRE 16 -1 (-4025 3375)(-2625 3375);
FORCEPROP 2 LAST SIG_NAME SMB_BMC_MM16_R4_SDA
J 0
(-3835 3385);
DISPLAY 0.851064 (-3835 3385);
WIRE 16 -1 (-8450 5275)(-7350 5275);
FORCEPROP 2 LAST SIG_NAME FM_P12V_HSC_ENABLE
J 0
(-8460 5285);
DISPLAY 0.808511 (-8460 5285);
WIRE 16 -1 (-4025 3425)(-2625 3425);
FORCEPROP 2 LAST SIG_NAME SMB_BMC_MM16_R4_SCL
J 0
(-3835 3435);
DISPLAY 0.851064 (-3835 3435);
WIRE 16 -1 (-6675 3575)(-5575 3575);
FORCEPROP 2 LAST SIG_NAME GPU_FPGA_RST_N
J 0
(-6610 3585);
DISPLAY 0.851064 (-6610 3585);
WIRE 16 -1 (-5575 3425)(-6675 3425);
FORCEPROP 2 LAST SIG_NAME CLK_BUF1_GPU_FPGA_OE_R_N
J 0
(-6610 3435);
DISPLAY 0.808511 (-6610 3435);
WIRE 16 -1 (-8450 5075)(-7350 5075);
WIRE 16 -1 (-8450 5125)(-7350 5125);
FORCEPROP 2 LAST SIG_NAME FM_SOL_UART_CH_SEL
J 0
(-8460 5135);
DISPLAY 0.851064 (-8460 5135);
DOT 1 (-2200 4775);
DOT 1 (-2550 4225);
DOT 1 (-3825 3075);
DOT 1 (-5775 3075);
DOT 1 (-2250 4825);
QUIT
